(kicad_sch
	(version 20250114)
	(generator "eeschema")
	(generator_version "9.0")
	(paper "A3")
	(title_block
		(title "LPDDR4 Test Board")
		(date "2024-02-12")
		(rev "1.1.5")
	)
	(text "Close to \n1xVCCO_33\n1xVCCO_34\n"
		(exclude_from_sim no)
		(at 76.835 158.75 0)
		(effects
			(font
				(size 1.27 1.27)
			)
			(justify left bottom)
		)
	)
	(text "VCCO (13-16 banks) max: 3.6V"
		(exclude_from_sim no)
		(at 270.51 155.575 0)
		(effects
			(font
				(size 1.27 1.27)
			)
			(justify left bottom)
		)
	)
	(text "Close to \nVCCINT"
		(exclude_from_sim no)
		(at 76.835 61.595 0)
		(effects
			(font
				(size 1.27 1.27)
			)
			(justify left bottom)
		)
	)
	(text "Close to \nVCCAUX\n"
		(exclude_from_sim no)
		(at 76.835 118.745 0)
		(effects
			(font
				(size 1.27 1.27)
			)
			(justify left bottom)
		)
	)
	(text "Close to \nVCCBRAM"
		(exclude_from_sim no)
		(at 76.835 80.645 0)
		(effects
			(font
				(size 1.27 1.27)
			)
			(justify left bottom)
		)
	)
	(text "Decoupling referenced from 7 Series FPGAs\nPCB Design Guide UG483"
		(exclude_from_sim no)
		(at 76.835 49.53 0)
		(effects
			(font
				(size 1.27 1.27)
			)
			(justify left bottom)
		)
	)
	(text "VCCO (33-34 banks) max: 2.0V"
		(exclude_from_sim no)
		(at 270.51 148.59 0)
		(effects
			(font
				(size 1.27 1.27)
			)
			(justify left bottom)
		)
	)
	(text "Close to \n6xVCCO_33\n6xVCCO_34\n"
		(exclude_from_sim no)
		(at 76.835 177.8 0)
		(effects
			(font
				(size 1.27 1.27)
			)
			(justify left bottom)
		)
	)
	(text "VCCBATT max: 2.0V"
		(exclude_from_sim no)
		(at 282.575 121.92 0)
		(effects
			(font
				(size 1.27 1.27)
			)
			(justify left bottom)
		)
	)
	(text "POWER RAILS"
		(exclude_from_sim no)
		(at 317.5 100.965 0)
		(effects
			(font
				(size 2.4892 2.4892)
				(thickness 0.4978)
				(bold yes)
			)
			(justify left bottom)
		)
	)
	(text "VCCINT max: 1.1V"
		(exclude_from_sim no)
		(at 282.575 119.38 0)
		(effects
			(font
				(size 1.27 1.27)
			)
			(justify left bottom)
		)
	)
	(text "Close to \n7xVCCAUX\n1xVCCBATT\n1xVCCADC"
		(exclude_from_sim no)
		(at 76.835 141.605 0)
		(effects
			(font
				(size 1.27 1.27)
			)
			(justify left bottom)
		)
	)
	(text "Close to \n5xVCCO_13\n5xVCCO_14\n5xVCCO_15\n3xVCCO_16"
		(exclude_from_sim no)
		(at 76.835 238.76 0)
		(effects
			(font
				(size 1.27 1.27)
			)
			(justify left bottom)
		)
	)
	(text "VCCBRAM max: 1.1V"
		(exclude_from_sim no)
		(at 282.575 124.46 0)
		(effects
			(font
				(size 1.27 1.27)
			)
			(justify left bottom)
		)
	)
	(text "VCCAUX max: 2.0V"
		(exclude_from_sim no)
		(at 282.575 116.84 0)
		(effects
			(font
				(size 1.27 1.27)
			)
			(justify left bottom)
		)
	)
	(text "Close to \n1xVCCO_13\n1xVCCO_14\n1xVCCO_15\n1xVCCO_16"
		(exclude_from_sim no)
		(at 76.835 219.71 0)
		(effects
			(font
				(size 1.27 1.27)
			)
			(justify left bottom)
		)
	)
	(text "Close to \n15xVCCINT\n3xVCCBRAM"
		(exclude_from_sim no)
		(at 76.835 103.505 0)
		(effects
			(font
				(size 1.27 1.27)
			)
			(justify left bottom)
		)
	)
	(text "VCCADC max: 2.0V"
		(exclude_from_sim no)
		(at 282.575 127 0)
		(effects
			(font
				(size 1.27 1.27)
			)
			(justify left bottom)
		)
	)
	(text "Close to \nVCCO_0"
		(exclude_from_sim no)
		(at 76.835 194.945 0)
		(effects
			(font
				(size 1.27 1.27)
			)
			(justify left bottom)
		)
	)
	(junction
		(at 140.97 227.33)
		(diameter 0)
		(color 0 0 0 0)
	)
	(junction
		(at 189.865 227.33)
		(diameter 0)
		(color 0 0 0 0)
	)
	(junction
		(at 92.075 93.98)
		(diameter 0)
		(color 0 0 0 0)
	)
	(junction
		(at 175.895 93.98)
		(diameter 0)
		(color 0 0 0 0)
	)
	(junction
		(at 147.955 170.18)
		(diameter 0)
		(color 0 0 0 0)
	)
	(junction
		(at 99.06 113.03)
		(diameter 0)
		(color 0 0 0 0)
	)
	(junction
		(at 140.97 132.08)
		(diameter 0)
		(color 0 0 0 0)
	)
	(junction
		(at 147.955 93.98)
		(diameter 0)
		(color 0 0 0 0)
	)
	(junction
		(at 133.985 227.33)
		(diameter 0)
		(color 0 0 0 0)
	)
	(junction
		(at 127 132.08)
		(diameter 0)
		(color 0 0 0 0)
	)
	(junction
		(at 113.03 113.03)
		(diameter 0)
		(color 0 0 0 0)
	)
	(junction
		(at 113.03 93.98)
		(diameter 0)
		(color 0 0 0 0)
	)
	(junction
		(at 106.045 93.98)
		(diameter 0)
		(color 0 0 0 0)
	)
	(junction
		(at 92.075 132.08)
		(diameter 0)
		(color 0 0 0 0)
	)
	(junction
		(at 92.075 208.28)
		(diameter 0)
		(color 0 0 0 0)
	)
	(junction
		(at 140.97 170.18)
		(diameter 0)
		(color 0 0 0 0)
	)
	(junction
		(at 92.075 170.18)
		(diameter 0)
		(color 0 0 0 0)
	)
	(junction
		(at 99.06 208.28)
		(diameter 0)
		(color 0 0 0 0)
	)
	(junction
		(at 99.06 74.93)
		(diameter 0)
		(color 0 0 0 0)
	)
	(junction
		(at 203.835 227.33)
		(diameter 0)
		(color 0 0 0 0)
	)
	(junction
		(at 203.835 93.98)
		(diameter 0)
		(color 0 0 0 0)
	)
	(junction
		(at 106.045 170.18)
		(diameter 0)
		(color 0 0 0 0)
	)
	(junction
		(at 106.045 113.03)
		(diameter 0)
		(color 0 0 0 0)
	)
	(junction
		(at 161.925 227.33)
		(diameter 0)
		(color 0 0 0 0)
	)
	(junction
		(at 182.88 227.33)
		(diameter 0)
		(color 0 0 0 0)
	)
	(junction
		(at 113.03 132.08)
		(diameter 0)
		(color 0 0 0 0)
	)
	(junction
		(at 168.91 227.33)
		(diameter 0)
		(color 0 0 0 0)
	)
	(junction
		(at 127 227.33)
		(diameter 0)
		(color 0 0 0 0)
	)
	(junction
		(at 154.94 227.33)
		(diameter 0)
		(color 0 0 0 0)
	)
	(junction
		(at 120.015 93.98)
		(diameter 0)
		(color 0 0 0 0)
	)
	(junction
		(at 154.94 93.98)
		(diameter 0)
		(color 0 0 0 0)
	)
	(junction
		(at 182.88 93.98)
		(diameter 0)
		(color 0 0 0 0)
	)
	(junction
		(at 161.925 170.18)
		(diameter 0)
		(color 0 0 0 0)
	)
	(junction
		(at 312.42 166.37)
		(diameter 0)
		(color 0 0 0 0)
	)
	(junction
		(at 120.015 227.33)
		(diameter 0)
		(color 0 0 0 0)
	)
	(junction
		(at 106.045 132.08)
		(diameter 0)
		(color 0 0 0 0)
	)
	(junction
		(at 99.06 132.08)
		(diameter 0)
		(color 0 0 0 0)
	)
	(junction
		(at 133.985 132.08)
		(diameter 0)
		(color 0 0 0 0)
	)
	(junction
		(at 92.075 151.13)
		(diameter 0)
		(color 0 0 0 0)
	)
	(junction
		(at 113.03 227.33)
		(diameter 0)
		(color 0 0 0 0)
	)
	(junction
		(at 127 93.98)
		(diameter 0)
		(color 0 0 0 0)
	)
	(junction
		(at 92.075 189.23)
		(diameter 0)
		(color 0 0 0 0)
	)
	(junction
		(at 99.06 227.33)
		(diameter 0)
		(color 0 0 0 0)
	)
	(junction
		(at 168.91 93.98)
		(diameter 0)
		(color 0 0 0 0)
	)
	(junction
		(at 106.045 208.28)
		(diameter 0)
		(color 0 0 0 0)
	)
	(junction
		(at 154.94 170.18)
		(diameter 0)
		(color 0 0 0 0)
	)
	(junction
		(at 196.85 93.98)
		(diameter 0)
		(color 0 0 0 0)
	)
	(junction
		(at 133.985 93.98)
		(diameter 0)
		(color 0 0 0 0)
	)
	(junction
		(at 92.71 74.93)
		(diameter 0)
		(color 0 0 0 0)
	)
	(junction
		(at 99.06 93.98)
		(diameter 0)
		(color 0 0 0 0)
	)
	(junction
		(at 106.045 227.33)
		(diameter 0)
		(color 0 0 0 0)
	)
	(junction
		(at 140.97 93.98)
		(diameter 0)
		(color 0 0 0 0)
	)
	(junction
		(at 92.075 113.03)
		(diameter 0)
		(color 0 0 0 0)
	)
	(junction
		(at 196.85 227.33)
		(diameter 0)
		(color 0 0 0 0)
	)
	(junction
		(at 99.06 170.18)
		(diameter 0)
		(color 0 0 0 0)
	)
	(junction
		(at 175.895 227.33)
		(diameter 0)
		(color 0 0 0 0)
	)
	(junction
		(at 189.865 93.98)
		(diameter 0)
		(color 0 0 0 0)
	)
	(junction
		(at 127 170.18)
		(diameter 0)
		(color 0 0 0 0)
	)
	(junction
		(at 161.925 93.98)
		(diameter 0)
		(color 0 0 0 0)
	)
	(junction
		(at 120.015 170.18)
		(diameter 0)
		(color 0 0 0 0)
	)
	(junction
		(at 113.03 170.18)
		(diameter 0)
		(color 0 0 0 0)
	)
	(junction
		(at 147.955 227.33)
		(diameter 0)
		(color 0 0 0 0)
	)
	(junction
		(at 133.985 170.18)
		(diameter 0)
		(color 0 0 0 0)
	)
	(junction
		(at 120.015 132.08)
		(diameter 0)
		(color 0 0 0 0)
	)
	(junction
		(at 92.075 227.33)
		(diameter 0)
		(color 0 0 0 0)
	)
	(no_connect
		(at 314.96 133.35)
	)
	(no_connect
		(at 314.96 135.89)
	)
	(no_connect
		(at 314.96 130.81)
	)
	(no_connect
		(at 314.96 138.43)
	)
	(no_connect
		(at 314.96 140.97)
	)
	(wire
		(pts
			(xy 127 228.6) (xy 127 227.33)
		)
		(stroke
			(width 0)
			(type default)
		)
	)
	(wire
		(pts
			(xy 113.03 93.98) (xy 120.015 93.98)
		)
		(stroke
			(width 0)
			(type default)
		)
	)
	(wire
		(pts
			(xy 99.06 177.8) (xy 99.06 176.53)
		)
		(stroke
			(width 0)
			(type default)
		)
	)
	(wire
		(pts
			(xy 106.045 101.6) (xy 106.045 100.33)
		)
		(stroke
			(width 0)
			(type default)
		)
	)
	(wire
		(pts
			(xy 161.925 177.8) (xy 161.925 176.53)
		)
		(stroke
			(width 0)
			(type default)
		)
	)
	(wire
		(pts
			(xy 113.03 227.33) (xy 120.015 227.33)
		)
		(stroke
			(width 0)
			(type default)
		)
	)
	(wire
		(pts
			(xy 147.955 228.6) (xy 147.955 227.33)
		)
		(stroke
			(width 0)
			(type default)
		)
	)
	(wire
		(pts
			(xy 92.075 101.6) (xy 92.075 100.33)
		)
		(stroke
			(width 0)
			(type default)
		)
	)
	(wire
		(pts
			(xy 113.03 234.95) (xy 113.03 233.68)
		)
		(stroke
			(width 0)
			(type default)
		)
	)
	(wire
		(pts
			(xy 210.82 234.95) (xy 210.82 233.68)
		)
		(stroke
			(width 0)
			(type default)
		)
	)
	(wire
		(pts
			(xy 92.075 208.28) (xy 99.06 208.28)
		)
		(stroke
			(width 0)
			(type default)
		)
	)
	(wire
		(pts
			(xy 120.015 227.33) (xy 127 227.33)
		)
		(stroke
			(width 0)
			(type default)
		)
	)
	(wire
		(pts
			(xy 133.985 234.95) (xy 133.985 233.68)
		)
		(stroke
			(width 0)
			(type default)
		)
	)
	(wire
		(pts
			(xy 90.17 74.93) (xy 92.71 74.93)
		)
		(stroke
			(width 0)
			(type default)
		)
	)
	(wire
		(pts
			(xy 161.925 227.33) (xy 168.91 227.33)
		)
		(stroke
			(width 0)
			(type default)
		)
	)
	(wire
		(pts
			(xy 120.015 95.25) (xy 120.015 93.98)
		)
		(stroke
			(width 0)
			(type default)
		)
	)
	(wire
		(pts
			(xy 106.045 234.95) (xy 106.045 233.68)
		)
		(stroke
			(width 0)
			(type default)
		)
	)
	(wire
		(pts
			(xy 113.03 177.8) (xy 113.03 176.53)
		)
		(stroke
			(width 0)
			(type default)
		)
	)
	(wire
		(pts
			(xy 182.88 95.25) (xy 182.88 93.98)
		)
		(stroke
			(width 0)
			(type default)
		)
	)
	(wire
		(pts
			(xy 92.075 114.3) (xy 92.075 113.03)
		)
		(stroke
			(width 0)
			(type default)
		)
	)
	(wire
		(pts
			(xy 127 170.18) (xy 133.985 170.18)
		)
		(stroke
			(width 0)
			(type default)
		)
	)
	(wire
		(pts
			(xy 140.97 234.95) (xy 140.97 233.68)
		)
		(stroke
			(width 0)
			(type default)
		)
	)
	(wire
		(pts
			(xy 89.535 93.98) (xy 92.075 93.98)
		)
		(stroke
			(width 0)
			(type default)
		)
	)
	(wire
		(pts
			(xy 147.955 170.18) (xy 154.94 170.18)
		)
		(stroke
			(width 0)
			(type default)
		)
	)
	(wire
		(pts
			(xy 106.045 93.98) (xy 113.03 93.98)
		)
		(stroke
			(width 0)
			(type default)
		)
	)
	(wire
		(pts
			(xy 140.97 132.08) (xy 147.955 132.08)
		)
		(stroke
			(width 0)
			(type default)
		)
	)
	(wire
		(pts
			(xy 99.06 195.58) (xy 99.06 196.85)
		)
		(stroke
			(width 0)
			(type default)
		)
	)
	(wire
		(pts
			(xy 120.015 132.08) (xy 127 132.08)
		)
		(stroke
			(width 0)
			(type default)
		)
	)
	(wire
		(pts
			(xy 99.06 139.7) (xy 99.06 138.43)
		)
		(stroke
			(width 0)
			(type default)
		)
	)
	(wire
		(pts
			(xy 106.045 113.03) (xy 113.03 113.03)
		)
		(stroke
			(width 0)
			(type default)
		)
	)
	(wire
		(pts
			(xy 99.06 113.03) (xy 106.045 113.03)
		)
		(stroke
			(width 0)
			(type default)
		)
	)
	(wire
		(pts
			(xy 99.06 114.3) (xy 99.06 113.03)
		)
		(stroke
			(width 0)
			(type default)
		)
	)
	(wire
		(pts
			(xy 203.835 101.6) (xy 203.835 100.33)
		)
		(stroke
			(width 0)
			(type default)
		)
	)
	(wire
		(pts
			(xy 189.865 93.98) (xy 196.85 93.98)
		)
		(stroke
			(width 0)
			(type default)
		)
	)
	(wire
		(pts
			(xy 89.535 132.08) (xy 92.075 132.08)
		)
		(stroke
			(width 0)
			(type default)
		)
	)
	(wire
		(pts
			(xy 127 132.08) (xy 133.985 132.08)
		)
		(stroke
			(width 0)
			(type default)
		)
	)
	(wire
		(pts
			(xy 189.865 100.33) (xy 189.865 101.6)
		)
		(stroke
			(width 0)
			(type default)
		)
	)
	(wire
		(pts
			(xy 99.06 132.08) (xy 106.045 132.08)
		)
		(stroke
			(width 0)
			(type default)
		)
	)
	(wire
		(pts
			(xy 99.06 82.55) (xy 99.06 81.28)
		)
		(stroke
			(width 0)
			(type default)
		)
	)
	(wire
		(pts
			(xy 89.535 227.33) (xy 92.075 227.33)
		)
		(stroke
			(width 0)
			(type default)
		)
	)
	(wire
		(pts
			(xy 189.865 95.25) (xy 189.865 93.98)
		)
		(stroke
			(width 0)
			(type default)
		)
	)
	(wire
		(pts
			(xy 92.075 133.35) (xy 92.075 132.08)
		)
		(stroke
			(width 0)
			(type default)
		)
	)
	(wire
		(pts
			(xy 140.97 93.98) (xy 147.955 93.98)
		)
		(stroke
			(width 0)
			(type default)
		)
	)
	(wire
		(pts
			(xy 89.535 170.18) (xy 92.075 170.18)
		)
		(stroke
			(width 0)
			(type default)
		)
	)
	(wire
		(pts
			(xy 92.075 215.9) (xy 92.075 214.63)
		)
		(stroke
			(width 0)
			(type default)
		)
	)
	(wire
		(pts
			(xy 99.06 227.33) (xy 106.045 227.33)
		)
		(stroke
			(width 0)
			(type default)
		)
	)
	(wire
		(pts
			(xy 312.42 153.67) (xy 314.96 153.67)
		)
		(stroke
			(width 0)
			(type default)
		)
	)
	(wire
		(pts
			(xy 161.925 234.95) (xy 161.925 233.68)
		)
		(stroke
			(width 0)
			(type default)
		)
	)
	(wire
		(pts
			(xy 189.865 228.6) (xy 189.865 227.33)
		)
		(stroke
			(width 0)
			(type default)
		)
	)
	(wire
		(pts
			(xy 99.06 133.35) (xy 99.06 132.08)
		)
		(stroke
			(width 0)
			(type default)
		)
	)
	(wire
		(pts
			(xy 312.42 123.19) (xy 314.96 123.19)
		)
		(stroke
			(width 0)
			(type default)
		)
	)
	(wire
		(pts
			(xy 106.045 139.7) (xy 106.045 138.43)
		)
		(stroke
			(width 0)
			(type default)
		)
	)
	(wire
		(pts
			(xy 92.075 170.18) (xy 99.06 170.18)
		)
		(stroke
			(width 0)
			(type default)
		)
	)
	(wire
		(pts
			(xy 92.075 152.4) (xy 92.075 151.13)
		)
		(stroke
			(width 0)
			(type default)
		)
	)
	(wire
		(pts
			(xy 92.075 228.6) (xy 92.075 227.33)
		)
		(stroke
			(width 0)
			(type default)
		)
	)
	(wire
		(pts
			(xy 140.97 228.6) (xy 140.97 227.33)
		)
		(stroke
			(width 0)
			(type default)
		)
	)
	(wire
		(pts
			(xy 147.955 133.35) (xy 147.955 132.08)
		)
		(stroke
			(width 0)
			(type default)
		)
	)
	(wire
		(pts
			(xy 203.835 95.25) (xy 203.835 93.98)
		)
		(stroke
			(width 0)
			(type default)
		)
	)
	(wire
		(pts
			(xy 161.925 95.25) (xy 161.925 93.98)
		)
		(stroke
			(width 0)
			(type default)
		)
	)
	(wire
		(pts
			(xy 99.06 170.18) (xy 106.045 170.18)
		)
		(stroke
			(width 0)
			(type default)
		)
	)
	(wire
		(pts
			(xy 99.06 234.95) (xy 99.06 233.68)
		)
		(stroke
			(width 0)
			(type default)
		)
	)
	(wire
		(pts
			(xy 99.06 190.5) (xy 99.06 189.23)
		)
		(stroke
			(width 0)
			(type default)
		)
	)
	(wire
		(pts
			(xy 106.045 209.55) (xy 106.045 208.28)
		)
		(stroke
			(width 0)
			(type default)
		)
	)
	(wire
		(pts
			(xy 312.42 113.03) (xy 314.96 113.03)
		)
		(stroke
			(width 0)
			(type default)
		)
	)
	(wire
		(pts
			(xy 140.97 95.25) (xy 140.97 93.98)
		)
		(stroke
			(width 0)
			(type default)
		)
	)
	(wire
		(pts
			(xy 120.015 139.7) (xy 120.015 138.43)
		)
		(stroke
			(width 0)
			(type default)
		)
	)
	(wire
		(pts
			(xy 175.895 228.6) (xy 175.895 227.33)
		)
		(stroke
			(width 0)
			(type default)
		)
	)
	(wire
		(pts
			(xy 120.015 170.18) (xy 127 170.18)
		)
		(stroke
			(width 0)
			(type default)
		)
	)
	(wire
		(pts
			(xy 140.97 101.6) (xy 140.97 100.33)
		)
		(stroke
			(width 0)
			(type default)
		)
	)
	(wire
		(pts
			(xy 92.075 120.65) (xy 92.075 119.38)
		)
		(stroke
			(width 0)
			(type default)
		)
	)
	(wire
		(pts
			(xy 161.925 228.6) (xy 161.925 227.33)
		)
		(stroke
			(width 0)
			(type default)
		)
	)
	(wire
		(pts
			(xy 168.91 93.98) (xy 175.895 93.98)
		)
		(stroke
			(width 0)
			(type default)
		)
	)
	(wire
		(pts
			(xy 140.97 133.35) (xy 140.97 132.08)
		)
		(stroke
			(width 0)
			(type default)
		)
	)
	(wire
		(pts
			(xy 312.42 146.05) (xy 314.96 146.05)
		)
		(stroke
			(width 0)
			(type default)
		)
	)
	(wire
		(pts
			(xy 120.015 133.35) (xy 120.015 132.08)
		)
		(stroke
			(width 0)
			(type default)
		)
	)
	(wire
		(pts
			(xy 133.985 171.45) (xy 133.985 170.18)
		)
		(stroke
			(width 0)
			(type default)
		)
	)
	(wire
		(pts
			(xy 154.94 170.18) (xy 161.925 170.18)
		)
		(stroke
			(width 0)
			(type default)
		)
	)
	(wire
		(pts
			(xy 147.955 95.25) (xy 147.955 93.98)
		)
		(stroke
			(width 0)
			(type default)
		)
	)
	(wire
		(pts
			(xy 89.535 208.28) (xy 92.075 208.28)
		)
		(stroke
			(width 0)
			(type default)
		)
	)
	(wire
		(pts
			(xy 113.03 95.25) (xy 113.03 93.98)
		)
		(stroke
			(width 0)
			(type default)
		)
	)
	(wire
		(pts
			(xy 127 138.43) (xy 127 139.7)
		)
		(stroke
			(width 0)
			(type default)
		)
	)
	(wire
		(pts
			(xy 92.075 177.8) (xy 92.075 176.53)
		)
		(stroke
			(width 0)
			(type default)
		)
	)
	(wire
		(pts
			(xy 120.015 101.6) (xy 120.015 100.33)
		)
		(stroke
			(width 0)
			(type default)
		)
	)
	(wire
		(pts
			(xy 196.85 93.98) (xy 203.835 93.98)
		)
		(stroke
			(width 0)
			(type default)
		)
	)
	(wire
		(pts
			(xy 140.97 171.45) (xy 140.97 170.18)
		)
		(stroke
			(width 0)
			(type default)
		)
	)
	(wire
		(pts
			(xy 154.94 227.33) (xy 161.925 227.33)
		)
		(stroke
			(width 0)
			(type default)
		)
	)
	(wire
		(pts
			(xy 99.06 152.4) (xy 99.06 151.13)
		)
		(stroke
			(width 0)
			(type default)
		)
	)
	(wire
		(pts
			(xy 168.91 177.8) (xy 168.91 176.53)
		)
		(stroke
			(width 0)
			(type default)
		)
	)
	(wire
		(pts
			(xy 120.015 120.65) (xy 120.015 119.38)
		)
		(stroke
			(width 0)
			(type default)
		)
	)
	(wire
		(pts
			(xy 175.895 227.33) (xy 182.88 227.33)
		)
		(stroke
			(width 0)
			(type default)
		)
	)
	(wire
		(pts
			(xy 89.535 55.88) (xy 92.075 55.88)
		)
		(stroke
			(width 0)
			(type default)
		)
	)
	(wire
		(pts
			(xy 106.045 208.28) (xy 113.03 208.28)
		)
		(stroke
			(width 0)
			(type default)
		)
	)
	(wire
		(pts
			(xy 210.82 101.6) (xy 210.82 100.33)
		)
		(stroke
			(width 0)
			(type default)
		)
	)
	(wire
		(pts
			(xy 99.06 101.6) (xy 99.06 100.33)
		)
		(stroke
			(width 0)
			(type default)
		)
	)
	(wire
		(pts
			(xy 92.075 227.33) (xy 99.06 227.33)
		)
		(stroke
			(width 0)
			(type default)
		)
	)
	(wire
		(pts
			(xy 92.075 189.23) (xy 92.075 190.5)
		)
		(stroke
			(width 0)
			(type default)
		)
	)
	(wire
		(pts
			(xy 113.03 120.65) (xy 113.03 119.38)
		)
		(stroke
			(width 0)
			(type default)
		)
	)
	(wire
		(pts
			(xy 106.045 215.9) (xy 106.045 214.63)
		)
		(stroke
			(width 0)
			(type default)
		)
	)
	(wire
		(pts
			(xy 92.075 195.58) (xy 92.075 196.85)
		)
		(stroke
			(width 0)
			(type default)
		)
	)
	(wire
		(pts
			(xy 113.03 113.03) (xy 120.015 113.03)
		)
		(stroke
			(width 0)
			(type default)
		)
	)
	(wire
		(pts
			(xy 161.925 101.6) (xy 161.925 100.33)
		)
		(stroke
			(width 0)
			(type default)
		)
	)
	(wire
		(pts
			(xy 113.03 215.9) (xy 113.03 214.63)
		)
		(stroke
			(width 0)
			(type default)
		)
	)
	(wire
		(pts
			(xy 210.82 95.25) (xy 210.82 93.98)
		)
		(stroke
			(width 0)
			(type default)
		)
	)
	(wire
		(pts
			(xy 312.42 115.57) (xy 314.96 115.57)
		)
		(stroke
			(width 0)
			(type default)
		)
	)
	(wire
		(pts
			(xy 113.03 209.55) (xy 113.03 208.28)
		)
		(stroke
			(width 0)
			(type default)
		)
	)
	(wire
		(pts
			(xy 140.97 139.7) (xy 140.97 138.43)
		)
		(stroke
			(width 0)
			(type default)
		)
	)
	(wire
		(pts
			(xy 203.835 228.6) (xy 203.835 227.33)
		)
		(stroke
			(width 0)
			(type default)
		)
	)
	(wire
		(pts
			(xy 127 177.8) (xy 127 176.53)
		)
		(stroke
			(width 0)
			(type default)
		)
	)
	(wire
		(pts
			(xy 92.075 132.08) (xy 99.06 132.08)
		)
		(stroke
			(width 0)
			(type default)
		)
	)
	(wire
		(pts
			(xy 89.535 113.03) (xy 92.075 113.03)
		)
		(stroke
			(width 0)
			(type default)
		)
	)
	(wire
		(pts
			(xy 113.03 139.7) (xy 113.03 138.43)
		)
		(stroke
			(width 0)
			(type default)
		)
	)
	(wire
		(pts
			(xy 92.075 93.98) (xy 99.06 93.98)
		)
		(stroke
			(width 0)
			(type default)
		)
	)
	(wire
		(pts
			(xy 92.075 171.45) (xy 92.075 170.18)
		)
		(stroke
			(width 0)
			(type default)
		)
	)
	(wire
		(pts
			(xy 99.06 215.9) (xy 99.06 214.63)
		)
		(stroke
			(width 0)
			(type default)
		)
	)
	(wire
		(pts
			(xy 92.075 158.75) (xy 92.075 157.48)
		)
		(stroke
			(width 0)
			(type default)
		)
	)
	(wire
		(pts
			(xy 133.985 95.25) (xy 133.985 93.98)
		)
		(stroke
			(width 0)
			(type default)
		)
	)
	(wire
		(pts
			(xy 106.045 120.65) (xy 106.045 119.38)
		)
		(stroke
			(width 0)
			(type default)
		)
	)
	(wire
		(pts
			(xy 92.075 95.25) (xy 92.075 93.98)
		)
		(stroke
			(width 0)
			(type default)
		)
	)
	(wire
		(pts
			(xy 154.94 171.45) (xy 154.94 170.18)
		)
		(stroke
			(width 0)
			(type default)
		)
	)
	(wire
		(pts
			(xy 147.955 101.6) (xy 147.955 100.33)
		)
		(stroke
			(width 0)
			(type default)
		)
	)
	(wire
		(pts
			(xy 113.03 170.18) (xy 120.015 170.18)
		)
		(stroke
			(width 0)
			(type default)
		)
	)
	(wire
		(pts
			(xy 133.985 170.18) (xy 140.97 170.18)
		)
		(stroke
			(width 0)
			(type default)
		)
	)
	(wire
		(pts
			(xy 312.42 166.37) (xy 314.96 166.37)
		)
		(stroke
			(width 0)
			(type default)
		)
	)
	(wire
		(pts
			(xy 99.06 93.98) (xy 106.045 93.98)
		)
		(stroke
			(width 0)
			(type default)
		)
	)
	(wire
		(pts
			(xy 175.895 234.95) (xy 175.895 233.68)
		)
		(stroke
			(width 0)
			(type default)
		)
	)
	(wire
		(pts
			(xy 127 101.6) (xy 127 100.33)
		)
		(stroke
			(width 0)
			(type default)
		)
	)
	(wire
		(pts
			(xy 120.015 114.3) (xy 120.015 113.03)
		)
		(stroke
			(width 0)
			(type default)
		)
	)
	(wire
		(pts
			(xy 133.985 139.7) (xy 133.985 138.43)
		)
		(stroke
			(width 0)
			(type default)
		)
	)
	(wire
		(pts
			(xy 312.42 120.65) (xy 314.96 120.65)
		)
		(stroke
			(width 0)
			(type default)
		)
	)
	(wire
		(pts
			(xy 147.955 234.95) (xy 147.955 233.68)
		)
		(stroke
			(width 0)
			(type default)
		)
	)
	(wire
		(pts
			(xy 140.97 170.18) (xy 147.955 170.18)
		)
		(stroke
			(width 0)
			(type default)
		)
	)
	(wire
		(pts
			(xy 312.42 125.73) (xy 314.96 125.73)
		)
		(stroke
			(width 0)
			(type default)
		)
	)
	(wire
		(pts
			(xy 133.985 101.6) (xy 133.985 100.33)
		)
		(stroke
			(width 0)
			(type default)
		)
	)
	(wire
		(pts
			(xy 196.85 228.6) (xy 196.85 227.33)
		)
		(stroke
			(width 0)
			(type default)
		)
	)
	(wire
		(pts
			(xy 182.88 93.98) (xy 189.865 93.98)
		)
		(stroke
			(width 0)
			(type default)
		)
	)
	(wire
		(pts
			(xy 106.045 227.33) (xy 113.03 227.33)
		)
		(stroke
			(width 0)
			(type default)
		)
	)
	(wire
		(pts
			(xy 106.045 114.3) (xy 106.045 113.03)
		)
		(stroke
			(width 0)
			(type default)
		)
	)
	(wire
		(pts
			(xy 147.955 139.7) (xy 147.955 138.43)
		)
		(stroke
			(width 0)
			(type default)
		)
	)
	(wire
		(pts
			(xy 168.91 101.6) (xy 168.91 100.33)
		)
		(stroke
			(width 0)
			(type default)
		)
	)
	(wire
		(pts
			(xy 106.045 132.08) (xy 113.03 132.08)
		)
		(stroke
			(width 0)
			(type default)
		)
	)
	(wire
		(pts
			(xy 113.03 132.08) (xy 120.015 132.08)
		)
		(stroke
			(width 0)
			(type default)
		)
	)
	(wire
		(pts
			(xy 147.955 171.45) (xy 147.955 170.18)
		)
		(stroke
			(width 0)
			(type default)
		)
	)
	(wire
		(pts
			(xy 106.045 74.93) (xy 106.045 76.2)
		)
		(stroke
			(width 0)
			(type default)
		)
	)
	(wire
		(pts
			(xy 196.85 234.95) (xy 196.85 233.68)
		)
		(stroke
			(width 0)
			(type default)
		)
	)
	(wire
		(pts
			(xy 182.88 227.33) (xy 189.865 227.33)
		)
		(stroke
			(width 0)
			(type default)
		)
	)
	(wire
		(pts
			(xy 127 133.35) (xy 127 132.08)
		)
		(stroke
			(width 0)
			(type default)
		)
	)
	(wire
		(pts
			(xy 89.535 151.13) (xy 92.075 151.13)
		)
		(stroke
			(width 0)
			(type default)
		)
	)
	(wire
		(pts
			(xy 92.71 74.93) (xy 92.71 76.2)
		)
		(stroke
			(width 0)
			(type default)
		)
	)
	(wire
		(pts
			(xy 154.94 101.6) (xy 154.94 100.33)
		)
		(stroke
			(width 0)
			(type default)
		)
	)
	(wire
		(pts
			(xy 189.865 233.68) (xy 189.865 234.95)
		)
		(stroke
			(width 0)
			(type default)
		)
	)
	(wire
		(pts
			(xy 120.015 234.95) (xy 120.015 233.68)
		)
		(stroke
			(width 0)
			(type default)
		)
	)
	(wire
		(pts
			(xy 312.42 156.21) (xy 314.96 156.21)
		)
		(stroke
			(width 0)
			(type default)
		)
	)
	(wire
		(pts
			(xy 113.03 101.6) (xy 113.03 100.33)
		)
		(stroke
			(width 0)
			(type default)
		)
	)
	(wire
		(pts
			(xy 175.895 95.25) (xy 175.895 93.98)
		)
		(stroke
			(width 0)
			(type default)
		)
	)
	(wire
		(pts
			(xy 133.985 132.08) (xy 140.97 132.08)
		)
		(stroke
			(width 0)
			(type default)
		)
	)
	(wire
		(pts
			(xy 196.85 95.25) (xy 196.85 93.98)
		)
		(stroke
			(width 0)
			(type default)
		)
	)
	(wire
		(pts
			(xy 127 234.95) (xy 127 233.68)
		)
		(stroke
			(width 0)
			(type default)
		)
	)
	(wire
		(pts
			(xy 92.075 189.23) (xy 99.06 189.23)
		)
		(stroke
			(width 0)
			(type default)
		)
	)
	(wire
		(pts
			(xy 182.88 101.6) (xy 182.88 100.33)
		)
		(stroke
			(width 0)
			(type default)
		)
	)
	(wire
		(pts
			(xy 106.045 95.25) (xy 106.045 93.98)
		)
		(stroke
			(width 0)
			(type default)
		)
	)
	(wire
		(pts
			(xy 147.955 93.98) (xy 154.94 93.98)
		)
		(stroke
			(width 0)
			(type default)
		)
	)
	(wire
		(pts
			(xy 312.42 166.37) (xy 312.42 168.91)
		)
		(stroke
			(width 0)
			(type default)
		)
	)
	(wire
		(pts
			(xy 92.075 113.03) (xy 99.06 113.03)
		)
		(stroke
			(width 0)
			(type default)
		)
	)
	(wire
		(pts
			(xy 106.045 170.18) (xy 113.03 170.18)
		)
		(stroke
			(width 0)
			(type default)
		)
	)
	(wire
		(pts
			(xy 175.895 93.98) (xy 182.88 93.98)
		)
		(stroke
			(width 0)
			(type default)
		)
	)
	(wire
		(pts
			(xy 133.985 227.33) (xy 140.97 227.33)
		)
		(stroke
			(width 0)
			(type default)
		)
	)
	(wire
		(pts
			(xy 203.835 93.98) (xy 210.82 93.98)
		)
		(stroke
			(width 0)
			(type default)
		)
	)
	(wire
		(pts
			(xy 133.985 177.8) (xy 133.985 176.53)
		)
		(stroke
			(width 0)
			(type default)
		)
	)
	(wire
		(pts
			(xy 154.94 93.98) (xy 161.925 93.98)
		)
		(stroke
			(width 0)
			(type default)
		)
	)
	(wire
		(pts
			(xy 161.925 93.98) (xy 168.91 93.98)
		)
		(stroke
			(width 0)
			(type default)
		)
	)
	(wire
		(pts
			(xy 189.865 227.33) (xy 196.85 227.33)
		)
		(stroke
			(width 0)
			(type default)
		)
	)
	(wire
		(pts
			(xy 133.985 133.35) (xy 133.985 132.08)
		)
		(stroke
			(width 0)
			(type default)
		)
	)
	(wire
		(pts
			(xy 106.045 133.35) (xy 106.045 132.08)
		)
		(stroke
			(width 0)
			(type default)
		)
	)
	(wire
		(pts
			(xy 182.88 234.95) (xy 182.88 233.68)
		)
		(stroke
			(width 0)
			(type default)
		)
	)
	(wire
		(pts
			(xy 113.03 228.6) (xy 113.03 227.33)
		)
		(stroke
			(width 0)
			(type default)
		)
	)
	(wire
		(pts
			(xy 312.42 163.83) (xy 312.42 166.37)
		)
		(stroke
			(width 0)
			(type default)
		)
	)
	(wire
		(pts
			(xy 168.91 228.6) (xy 168.91 227.33)
		)
		(stroke
			(width 0)
			(type default)
		)
	)
	(wire
		(pts
			(xy 120.015 171.45) (xy 120.015 170.18)
		)
		(stroke
			(width 0)
			(type default)
		)
	)
	(wire
		(pts
			(xy 120.015 93.98) (xy 127 93.98)
		)
		(stroke
			(width 0)
			(type default)
		)
	)
	(wire
		(pts
			(xy 99.06 171.45) (xy 99.06 170.18)
		)
		(stroke
			(width 0)
			(type default)
		)
	)
	(wire
		(pts
			(xy 168.91 234.95) (xy 168.91 233.68)
		)
		(stroke
			(width 0)
			(type default)
		)
	)
	(wire
		(pts
			(xy 168.91 95.25) (xy 168.91 93.98)
		)
		(stroke
			(width 0)
			(type default)
		)
	)
	(wire
		(pts
			(xy 154.94 234.95) (xy 154.94 233.68)
		)
		(stroke
			(width 0)
			(type default)
		)
	)
	(wire
		(pts
			(xy 133.985 93.98) (xy 140.97 93.98)
		)
		(stroke
			(width 0)
			(type default)
		)
	)
	(wire
		(pts
			(xy 120.015 177.8) (xy 120.015 176.53)
		)
		(stroke
			(width 0)
			(type default)
		)
	)
	(wire
		(pts
			(xy 92.075 151.13) (xy 99.06 151.13)
		)
		(stroke
			(width 0)
			(type default)
		)
	)
	(wire
		(pts
			(xy 92.075 63.5) (xy 92.075 62.23)
		)
		(stroke
			(width 0)
			(type default)
		)
	)
	(wire
		(pts
			(xy 147.955 227.33) (xy 154.94 227.33)
		)
		(stroke
			(width 0)
			(type default)
		)
	)
	(wire
		(pts
			(xy 92.075 139.7) (xy 92.075 138.43)
		)
		(stroke
			(width 0)
			(type default)
		)
	)
	(wire
		(pts
			(xy 168.91 227.33) (xy 175.895 227.33)
		)
		(stroke
			(width 0)
			(type default)
		)
	)
	(wire
		(pts
			(xy 314.96 163.83) (xy 312.42 163.83)
		)
		(stroke
			(width 0)
			(type default)
		)
	)
	(wire
		(pts
			(xy 92.71 74.93) (xy 99.06 74.93)
		)
		(stroke
			(width 0)
			(type default)
		)
	)
	(wire
		(pts
			(xy 140.97 177.8) (xy 140.97 176.53)
		)
		(stroke
			(width 0)
			(type default)
		)
	)
	(wire
		(pts
			(xy 99.06 209.55) (xy 99.06 208.28)
		)
		(stroke
			(width 0)
			(type default)
		)
	)
	(wire
		(pts
			(xy 312.42 151.13) (xy 314.96 151.13)
		)
		(stroke
			(width 0)
			(type default)
		)
	)
	(wire
		(pts
			(xy 99.06 158.75) (xy 99.06 157.48)
		)
		(stroke
			(width 0)
			(type default)
		)
	)
	(wire
		(pts
			(xy 106.045 177.8) (xy 106.045 176.53)
		)
		(stroke
			(width 0)
			(type default)
		)
	)
	(wire
		(pts
			(xy 92.075 55.88) (xy 92.075 57.15)
		)
		(stroke
			(width 0)
			(type default)
		)
	)
	(wire
		(pts
			(xy 127 227.33) (xy 133.985 227.33)
		)
		(stroke
			(width 0)
			(type default)
		)
	)
	(wire
		(pts
			(xy 154.94 95.25) (xy 154.94 93.98)
		)
		(stroke
			(width 0)
			(type default)
		)
	)
	(wire
		(pts
			(xy 175.895 101.6) (xy 175.895 100.33)
		)
		(stroke
			(width 0)
			(type default)
		)
	)
	(wire
		(pts
			(xy 312.42 118.11) (xy 314.96 118.11)
		)
		(stroke
			(width 0)
			(type default)
		)
	)
	(wire
		(pts
			(xy 140.97 227.33) (xy 147.955 227.33)
		)
		(stroke
			(width 0)
			(type default)
		)
	)
	(wire
		(pts
			(xy 127 95.25) (xy 127 93.98)
		)
		(stroke
			(width 0)
			(type default)
		)
	)
	(wire
		(pts
			(xy 210.82 228.6) (xy 210.82 227.33)
		)
		(stroke
			(width 0)
			(type default)
		)
	)
	(wire
		(pts
			(xy 106.045 82.55) (xy 106.045 81.28)
		)
		(stroke
			(width 0)
			(type default)
		)
	)
	(wire
		(pts
			(xy 92.075 234.95) (xy 92.075 233.68)
		)
		(stroke
			(width 0)
			(type default)
		)
	)
	(wire
		(pts
			(xy 106.045 171.45) (xy 106.045 170.18)
		)
		(stroke
			(width 0)
			(type default)
		)
	)
	(wire
		(pts
			(xy 120.015 228.6) (xy 120.015 227.33)
		)
		(stroke
			(width 0)
			(type default)
		)
	)
	(wire
		(pts
			(xy 99.06 120.65) (xy 99.06 119.38)
		)
		(stroke
			(width 0)
			(type default)
		)
	)
	(wire
		(pts
			(xy 99.06 74.93) (xy 106.045 74.93)
		)
		(stroke
			(width 0)
			(type default)
		)
	)
	(wire
		(pts
			(xy 92.71 82.55) (xy 92.71 81.28)
		)
		(stroke
			(width 0)
			(type default)
		)
	)
	(wire
		(pts
			(xy 161.925 171.45) (xy 161.925 170.18)
		)
		(stroke
			(width 0)
			(type default)
		)
	)
	(wire
		(pts
			(xy 106.045 228.6) (xy 106.045 227.33)
		)
		(stroke
			(width 0)
			(type default)
		)
	)
	(wire
		(pts
			(xy 99.06 228.6) (xy 99.06 227.33)
		)
		(stroke
			(width 0)
			(type default)
		)
	)
	(wire
		(pts
			(xy 99.06 74.93) (xy 99.06 76.2)
		)
		(stroke
			(width 0)
			(type default)
		)
	)
	(wire
		(pts
			(xy 147.955 177.8) (xy 147.955 176.53)
		)
		(stroke
			(width 0)
			(type default)
		)
	)
	(wire
		(pts
			(xy 203.835 234.95) (xy 203.835 233.68)
		)
		(stroke
			(width 0)
			(type default)
		)
	)
	(wire
		(pts
			(xy 161.925 170.18) (xy 168.91 170.18)
		)
		(stroke
			(width 0)
			(type default)
		)
	)
	(wire
		(pts
			(xy 113.03 171.45) (xy 113.03 170.18)
		)
		(stroke
			(width 0)
			(type default)
		)
	)
	(wire
		(pts
			(xy 312.42 158.75) (xy 314.96 158.75)
		)
		(stroke
			(width 0)
			(type default)
		)
	)
	(wire
		(pts
			(xy 168.91 171.45) (xy 168.91 170.18)
		)
		(stroke
			(width 0)
			(type default)
		)
	)
	(wire
		(pts
			(xy 203.835 227.33) (xy 210.82 227.33)
		)
		(stroke
			(width 0)
			(type default)
		)
	)
	(wire
		(pts
			(xy 99.06 208.28) (xy 106.045 208.28)
		)
		(stroke
			(width 0)
			(type default)
		)
	)
	(wire
		(pts
			(xy 154.94 177.8) (xy 154.94 176.53)
		)
		(stroke
			(width 0)
			(type default)
		)
	)
	(wire
		(pts
			(xy 312.42 148.59) (xy 314.96 148.59)
		)
		(stroke
			(width 0)
			(type default)
		)
	)
	(wire
		(pts
			(xy 133.985 228.6) (xy 133.985 227.33)
		)
		(stroke
			(width 0)
			(type default)
		)
	)
	(wire
		(pts
			(xy 113.03 114.3) (xy 113.03 113.03)
		)
		(stroke
			(width 0)
			(type default)
		)
	)
	(wire
		(pts
			(xy 127 171.45) (xy 127 170.18)
		)
		(stroke
			(width 0)
			(type default)
		)
	)
	(wire
		(pts
			(xy 182.88 228.6) (xy 182.88 227.33)
		)
		(stroke
			(width 0)
			(type default)
		)
	)
	(wire
		(pts
			(xy 196.85 227.33) (xy 203.835 227.33)
		)
		(stroke
			(width 0)
			(type default)
		)
	)
	(wire
		(pts
			(xy 99.06 95.25) (xy 99.06 93.98)
		)
		(stroke
			(width 0)
			(type default)
		)
	)
	(wire
		(pts
			(xy 196.85 101.6) (xy 196.85 100.33)
		)
		(stroke
			(width 0)
			(type default)
		)
	)
	(wire
		(pts
			(xy 92.075 208.28) (xy 92.075 209.55)
		)
		(stroke
			(width 0)
			(type default)
		)
	)
	(wire
		(pts
			(xy 127 93.98) (xy 133.985 93.98)
		)
		(stroke
			(width 0)
			(type default)
		)
	)
	(wire
		(pts
			(xy 154.94 228.6) (xy 154.94 227.33)
		)
		(stroke
			(width 0)
			(type default)
		)
	)
	(wire
		(pts
			(xy 89.535 189.23) (xy 92.075 189.23)
		)
		(stroke
			(width 0)
			(type default)
		)
	)
	(wire
		(pts
			(xy 113.03 133.35) (xy 113.03 132.08)
		)
		(stroke
			(width 0)
			(type default)
		)
	)
	(global_label "1V0_SYS"
		(shape input)
		(at 89.535 55.88 180)
		(fields_autoplaced yes)
		(effects
			(font
				(size 1.27 1.27)
			)
			(justify right)
		)
		(property "Intersheetrefs" "${INTERSHEET_REFS}"
			(at 79.2279 55.9594 0)
			(effects
				(font
					(size 1.27 1.27)
				)
				(justify right)
				(hide yes)
			)
		)
	)
	(global_label "VDDQ"
		(shape input)
		(at 312.42 146.05 180)
		(fields_autoplaced yes)
		(effects
			(font
				(size 1.27 1.27)
			)
			(justify right)
		)
		(property "Intersheetrefs" "${INTERSHEET_REFS}"
			(at 305.1368 145.9706 0)
			(effects
				(font
					(size 1.27 1.27)
				)
				(justify right)
				(hide yes)
			)
		)
	)
	(global_label "3V3_SYS"
		(shape input)
		(at 312.42 156.21 180)
		(fields_autoplaced yes)
		(effects
			(font
				(size 1.27 1.27)
			)
			(justify right)
		)
		(property "Intersheetrefs" "${INTERSHEET_REFS}"
			(at 302.1129 156.1306 0)
			(effects
				(font
					(size 1.27 1.27)
				)
				(justify right)
				(hide yes)
			)
		)
	)
	(global_label "1V0_SYS"
		(shape input)
		(at 89.535 93.98 180)
		(fields_autoplaced yes)
		(effects
			(font
				(size 1.27 1.27)
			)
			(justify right)
		)
		(property "Intersheetrefs" "${INTERSHEET_REFS}"
			(at 79.2279 94.0594 0)
			(effects
				(font
					(size 1.27 1.27)
				)
				(justify right)
				(hide yes)
			)
		)
	)
	(global_label "VDDQ"
		(shape input)
		(at 89.535 151.13 180)
		(fields_autoplaced yes)
		(effects
			(font
				(size 1.27 1.27)
			)
			(justify right)
		)
		(property "Intersheetrefs" "${INTERSHEET_REFS}"
			(at 82.2518 151.2094 0)
			(effects
				(font
					(size 1.27 1.27)
				)
				(justify right)
				(hide yes)
			)
		)
	)
	(global_label "VDDQ"
		(shape input)
		(at 312.42 148.59 180)
		(fields_autoplaced yes)
		(effects
			(font
				(size 1.27 1.27)
			)
			(justify right)
		)
		(property "Intersheetrefs" "${INTERSHEET_REFS}"
			(at 305.1368 148.5106 0)
			(effects
				(font
					(size 1.27 1.27)
				)
				(justify right)
				(hide yes)
			)
		)
	)
	(global_label "3V3_SYS"
		(shape input)
		(at 312.42 151.13 180)
		(fields_autoplaced yes)
		(effects
			(font
				(size 1.27 1.27)
			)
			(justify right)
		)
		(property "Intersheetrefs" "${INTERSHEET_REFS}"
			(at 302.1129 151.0506 0)
			(effects
				(font
					(size 1.27 1.27)
				)
				(justify right)
				(hide yes)
			)
		)
	)
	(global_label "1V0_SYS"
		(shape input)
		(at 312.42 118.11 180)
		(fields_autoplaced yes)
		(effects
			(font
				(size 1.27 1.27)
			)
			(justify right)
		)
		(property "Intersheetrefs" "${INTERSHEET_REFS}"
			(at 302.1129 118.0306 0)
			(effects
				(font
					(size 1.27 1.27)
				)
				(justify right)
				(hide yes)
			)
		)
	)
	(global_label "1V8_SYS"
		(shape input)
		(at 89.535 132.08 180)
		(fields_autoplaced yes)
		(effects
			(font
				(size 1.27 1.27)
			)
			(justify right)
		)
		(property "Intersheetrefs" "${INTERSHEET_REFS}"
			(at 79.2279 132.1594 0)
			(effects
				(font
					(size 1.27 1.27)
				)
				(justify right)
				(hide yes)
			)
		)
	)
	(global_label "3V3_SYS"
		(shape input)
		(at 89.535 227.33 180)
		(fields_autoplaced yes)
		(effects
			(font
				(size 1.27 1.27)
			)
			(justify right)
		)
		(property "Intersheetrefs" "${INTERSHEET_REFS}"
			(at 79.2279 227.4094 0)
			(effects
				(font
					(size 1.27 1.27)
				)
				(justify right)
				(hide yes)
			)
		)
	)
	(global_label "3V3_SYS"
		(shape input)
		(at 89.535 189.23 180)
		(fields_autoplaced yes)
		(effects
			(font
				(size 1.27 1.27)
			)
			(justify right)
		)
		(property "Intersheetrefs" "${INTERSHEET_REFS}"
			(at 79.2279 189.3094 0)
			(effects
				(font
					(size 1.27 1.27)
				)
				(justify right)
				(hide yes)
			)
		)
	)
	(global_label "1V0_SYS"
		(shape input)
		(at 90.17 74.93 180)
		(fields_autoplaced yes)
		(effects
			(font
				(size 1.27 1.27)
			)
			(justify right)
		)
		(property "Intersheetrefs" "${INTERSHEET_REFS}"
			(at 79.8629 75.0094 0)
			(effects
				(font
					(size 1.27 1.27)
				)
				(justify right)
				(hide yes)
			)
		)
	)
	(global_label "1V8_SYS"
		(shape input)
		(at 89.535 113.03 180)
		(fields_autoplaced yes)
		(effects
			(font
				(size 1.27 1.27)
			)
			(justify right)
		)
		(property "Intersheetrefs" "${INTERSHEET_REFS}"
			(at 79.2279 113.1094 0)
			(effects
				(font
					(size 1.27 1.27)
				)
				(justify right)
				(hide yes)
			)
		)
	)
	(global_label "3V3_SYS"
		(shape input)
		(at 89.535 208.28 180)
		(fields_autoplaced yes)
		(effects
			(font
				(size 1.27 1.27)
			)
			(justify right)
		)
		(property "Intersheetrefs" "${INTERSHEET_REFS}"
			(at 79.2279 208.3594 0)
			(effects
				(font
					(size 1.27 1.27)
				)
				(justify right)
				(hide yes)
			)
		)
	)
	(global_label "1V8_SYS"
		(shape input)
		(at 312.42 125.73 180)
		(fields_autoplaced yes)
		(effects
			(font
				(size 1.27 1.27)
			)
			(justify right)
		)
		(property "Intersheetrefs" "${INTERSHEET_REFS}"
			(at 302.1129 125.6506 0)
			(effects
				(font
					(size 1.27 1.27)
				)
				(justify right)
				(hide yes)
			)
		)
	)
	(global_label "1V8_SYS"
		(shape input)
		(at 312.42 115.57 180)
		(fields_autoplaced yes)
		(effects
			(font
				(size 1.27 1.27)
			)
			(justify right)
		)
		(property "Intersheetrefs" "${INTERSHEET_REFS}"
			(at 302.1129 115.4906 0)
			(effects
				(font
					(size 1.27 1.27)
				)
				(justify right)
				(hide yes)
			)
		)
	)
	(global_label "VDDQ"
		(shape input)
		(at 89.535 170.18 180)
		(fields_autoplaced yes)
		(effects
			(font
				(size 1.27 1.27)
			)
			(justify right)
		)
		(property "Intersheetrefs" "${INTERSHEET_REFS}"
			(at 82.2518 170.2594 0)
			(effects
				(font
					(size 1.27 1.27)
				)
				(justify right)
				(hide yes)
			)
		)
	)
	(global_label "1V8_SYS"
		(shape input)
		(at 312.42 120.65 180)
		(fields_autoplaced yes)
		(effects
			(font
				(size 1.27 1.27)
			)
			(justify right)
		)
		(property "Intersheetrefs" "${INTERSHEET_REFS}"
			(at 302.1129 120.5706 0)
			(effects
				(font
					(size 1.27 1.27)
				)
				(justify right)
				(hide yes)
			)
		)
	)
	(global_label "1V0_SYS"
		(shape input)
		(at 312.42 123.19 180)
		(fields_autoplaced yes)
		(effects
			(font
				(size 1.27 1.27)
			)
			(justify right)
		)
		(property "Intersheetrefs" "${INTERSHEET_REFS}"
			(at 302.1129 123.1106 0)
			(effects
				(font
					(size 1.27 1.27)
				)
				(justify right)
				(hide yes)
			)
		)
	)
	(global_label "3V3_SYS"
		(shape input)
		(at 312.42 113.03 180)
		(fields_autoplaced yes)
		(effects
			(font
				(size 1.27 1.27)
			)
			(justify right)
		)
		(property "Intersheetrefs" "${INTERSHEET_REFS}"
			(at 302.1129 112.9506 0)
			(effects
				(font
					(size 1.27 1.27)
				)
				(justify right)
				(hide yes)
			)
		)
	)
	(global_label "3V3_SYS"
		(shape input)
		(at 312.42 158.75 180)
		(fields_autoplaced yes)
		(effects
			(font
				(size 1.27 1.27)
			)
			(justify right)
		)
		(property "Intersheetrefs" "${INTERSHEET_REFS}"
			(at 302.1129 158.6706 0)
			(effects
				(font
					(size 1.27 1.27)
				)
				(justify right)
				(hide yes)
			)
		)
	)
	(global_label "3V3_SYS"
		(shape input)
		(at 312.42 153.67 180)
		(fields_autoplaced yes)
		(effects
			(font
				(size 1.27 1.27)
			)
			(justify right)
		)
		(property "Intersheetrefs" "${INTERSHEET_REFS}"
			(at 302.1129 153.5906 0)
			(effects
				(font
					(size 1.27 1.27)
				)
				(justify right)
				(hide yes)
			)
		)
	)
	(symbol
		(lib_id "antmicroCapacitorsmisc:C_100n_0201")
		(at 92.075 171.45 270)
		(unit 1)
		(exclude_from_sim no)
		(in_bom yes)
		(on_board yes)
		(dnp no)
		(property "Reference" "C35"
			(at 92.71 173.355 90)
			(effects
				(font
					(size 1.27 1.27)
					(thickness 0.15)
				)
				(justify left bottom)
			)
		)
		(property "Value" "C_100n_0201"
			(at 81.915 191.77 0)
			(effects
				(font
					(size 1.27 1.27)
					(thickness 0.15)
				)
				(justify left bottom)
				(hide yes)
			)
		)
		(property "Footprint" "antmicro-footprints:C_0201"
			(at 79.375 191.77 0)
			(effects
				(font
					(size 1.27 1.27)
					(thickness 0.15)
				)
				(justify left bottom)
				(hide yes)
			)
		)
		(property "Datasheet" " "
			(at 76.835 191.77 0)
			(effects
				(font
					(size 1.27 1.27)
					(thickness 0.15)
				)
				(justify left bottom)
				(hide yes)
			)
		)
		(property "Description" ""
			(at 92.075 171.45 0)
			(effects
				(font
					(size 1.27 1.27)
				)
			)
		)
		(property "Manufacturer" "Yaego"
			(at 71.755 191.77 0)
			(effects
				(font
					(size 1.27 1.27)
					(thickness 0.15)
				)
				(justify left bottom)
				(hide yes)
			)
		)
		(property "MPN" "CC0201KRX6S5BB104"
			(at 74.295 191.77 0)
			(effects
				(font
					(size 1.27 1.27)
					(thickness 0.15)
				)
				(justify left bottom)
				(hide yes)
			)
		)
		(property "Val" "100n"
			(at 92.71 177.165 90)
			(effects
				(font
					(size 1.27 1.27)
					(thickness 0.15)
				)
				(justify left bottom)
			)
		)
		(property "License" "Apache-2.0"
			(at 69.215 191.77 0)
			(effects
				(font
					(size 1.27 1.27)
					(thickness 0.15)
				)
				(justify left bottom)
				(hide yes)
			)
		)
		(property "Author" "Antmicro"
			(at 66.675 191.77 0)
			(effects
				(font
					(size 1.27 1.27)
					(thickness 0.15)
				)
				(justify left bottom)
				(hide yes)
			)
		)
		(property "Voltage" ""
			(at 64.135 191.77 0)
			(effects
				(font
					(size 1.27 1.27)
				)
				(justify left bottom)
				(hide yes)
			)
		)
		(property "Dielectric" ""
			(at 61.595 191.77 0)
			(effects
				(font
					(size 1.27 1.27)
				)
				(justify left bottom)
				(hide yes)
			)
		)
		(pin "1"
		)
		(pin "2"
		)
		(instances
			(project "lpddr4-test-board"
				(path ""
					(reference "C35")
					(unit 1)
				)
			)
		)
	)
	(symbol
		(lib_id "antmicroCapacitorsmisc:C_100n_0201")
		(at 99.06 171.45 270)
		(unit 1)
		(exclude_from_sim no)
		(in_bom yes)
		(on_board yes)
		(dnp no)
		(property "Reference" "C39"
			(at 99.695 173.355 90)
			(effects
				(font
					(size 1.27 1.27)
					(thickness 0.15)
				)
				(justify left bottom)
			)
		)
		(property "Value" "C_100n_0201"
			(at 88.9 191.77 0)
			(effects
				(font
					(size 1.27 1.27)
					(thickness 0.15)
				)
				(justify left bottom)
				(hide yes)
			)
		)
		(property "Footprint" "antmicro-footprints:C_0201"
			(at 86.36 191.77 0)
			(effects
				(font
					(size 1.27 1.27)
					(thickness 0.15)
				)
				(justify left bottom)
				(hide yes)
			)
		)
		(property "Datasheet" " "
			(at 83.82 191.77 0)
			(effects
				(font
					(size 1.27 1.27)
					(thickness 0.15)
				)
				(justify left bottom)
				(hide yes)
			)
		)
		(property "Description" ""
			(at 99.06 171.45 0)
			(effects
				(font
					(size 1.27 1.27)
				)
			)
		)
		(property "Manufacturer" "Yaego"
			(at 78.74 191.77 0)
			(effects
				(font
					(size 1.27 1.27)
					(thickness 0.15)
				)
				(justify left bottom)
				(hide yes)
			)
		)
		(property "MPN" "CC0201KRX6S5BB104"
			(at 81.28 191.77 0)
			(effects
				(font
					(size 1.27 1.27)
					(thickness 0.15)
				)
				(justify left bottom)
				(hide yes)
			)
		)
		(property "Val" "100n"
			(at 99.695 177.165 90)
			(effects
				(font
					(size 1.27 1.27)
					(thickness 0.15)
				)
				(justify left bottom)
			)
		)
		(property "License" "Apache-2.0"
			(at 76.2 191.77 0)
			(effects
				(font
					(size 1.27 1.27)
					(thickness 0.15)
				)
				(justify left bottom)
				(hide yes)
			)
		)
		(property "Author" "Antmicro"
			(at 73.66 191.77 0)
			(effects
				(font
					(size 1.27 1.27)
					(thickness 0.15)
				)
				(justify left bottom)
				(hide yes)
			)
		)
		(property "Voltage" ""
			(at 71.12 191.77 0)
			(effects
				(font
					(size 1.27 1.27)
				)
				(justify left bottom)
				(hide yes)
			)
		)
		(property "Dielectric" ""
			(at 68.58 191.77 0)
			(effects
				(font
					(size 1.27 1.27)
				)
				(justify left bottom)
				(hide yes)
			)
		)
		(pin "1"
		)
		(pin "2"
		)
		(instances
			(project "lpddr4-test-board"
				(path ""
					(reference "C39")
					(unit 1)
				)
			)
		)
	)
	(symbol
		(lib_id "antmicroCapacitorsmisc:C_100n_0201")
		(at 106.045 171.45 270)
		(unit 1)
		(exclude_from_sim no)
		(in_bom yes)
		(on_board yes)
		(dnp no)
		(property "Reference" "C43"
			(at 106.68 173.355 90)
			(effects
				(font
					(size 1.27 1.27)
					(thickness 0.15)
				)
				(justify left bottom)
			)
		)
		(property "Value" "C_100n_0201"
			(at 95.885 191.77 0)
			(effects
				(font
					(size 1.27 1.27)
					(thickness 0.15)
				)
				(justify left bottom)
				(hide yes)
			)
		)
		(property "Footprint" "antmicro-footprints:C_0201"
			(at 93.345 191.77 0)
			(effects
				(font
					(size 1.27 1.27)
					(thickness 0.15)
				)
				(justify left bottom)
				(hide yes)
			)
		)
		(property "Datasheet" " "
			(at 90.805 191.77 0)
			(effects
				(font
					(size 1.27 1.27)
					(thickness 0.15)
				)
				(justify left bottom)
				(hide yes)
			)
		)
		(property "Description" ""
			(at 106.045 171.45 0)
			(effects
				(font
					(size 1.27 1.27)
				)
			)
		)
		(property "Manufacturer" "Yaego"
			(at 85.725 191.77 0)
			(effects
				(font
					(size 1.27 1.27)
					(thickness 0.15)
				)
				(justify left bottom)
				(hide yes)
			)
		)
		(property "MPN" "CC0201KRX6S5BB104"
			(at 88.265 191.77 0)
			(effects
				(font
					(size 1.27 1.27)
					(thickness 0.15)
				)
				(justify left bottom)
				(hide yes)
			)
		)
		(property "Val" "100n"
			(at 106.68 177.165 90)
			(effects
				(font
					(size 1.27 1.27)
					(thickness 0.15)
				)
				(justify left bottom)
			)
		)
		(property "License" "Apache-2.0"
			(at 83.185 191.77 0)
			(effects
				(font
					(size 1.27 1.27)
					(thickness 0.15)
				)
				(justify left bottom)
				(hide yes)
			)
		)
		(property "Author" "Antmicro"
			(at 80.645 191.77 0)
			(effects
				(font
					(size 1.27 1.27)
					(thickness 0.15)
				)
				(justify left bottom)
				(hide yes)
			)
		)
		(property "Voltage" ""
			(at 78.105 191.77 0)
			(effects
				(font
					(size 1.27 1.27)
				)
				(justify left bottom)
				(hide yes)
			)
		)
		(property "Dielectric" ""
			(at 75.565 191.77 0)
			(effects
				(font
					(size 1.27 1.27)
				)
				(justify left bottom)
				(hide yes)
			)
		)
		(pin "1"
		)
		(pin "2"
		)
		(instances
			(project "lpddr4-test-board"
				(path ""
					(reference "C43")
					(unit 1)
				)
			)
		)
	)
	(symbol
		(lib_id "antmicroCapacitorsmisc:C_100n_0201")
		(at 113.03 171.45 270)
		(unit 1)
		(exclude_from_sim no)
		(in_bom yes)
		(on_board yes)
		(dnp no)
		(property "Reference" "C47"
			(at 113.665 173.355 90)
			(effects
				(font
					(size 1.27 1.27)
					(thickness 0.15)
				)
				(justify left bottom)
			)
		)
		(property "Value" "C_100n_0201"
			(at 102.87 191.77 0)
			(effects
				(font
					(size 1.27 1.27)
					(thickness 0.15)
				)
				(justify left bottom)
				(hide yes)
			)
		)
		(property "Footprint" "antmicro-footprints:C_0201"
			(at 100.33 191.77 0)
			(effects
				(font
					(size 1.27 1.27)
					(thickness 0.15)
				)
				(justify left bottom)
				(hide yes)
			)
		)
		(property "Datasheet" " "
			(at 97.79 191.77 0)
			(effects
				(font
					(size 1.27 1.27)
					(thickness 0.15)
				)
				(justify left bottom)
				(hide yes)
			)
		)
		(property "Description" ""
			(at 113.03 171.45 0)
			(effects
				(font
					(size 1.27 1.27)
				)
			)
		)
		(property "Manufacturer" "Yaego"
			(at 92.71 191.77 0)
			(effects
				(font
					(size 1.27 1.27)
					(thickness 0.15)
				)
				(justify left bottom)
				(hide yes)
			)
		)
		(property "MPN" "CC0201KRX6S5BB104"
			(at 95.25 191.77 0)
			(effects
				(font
					(size 1.27 1.27)
					(thickness 0.15)
				)
				(justify left bottom)
				(hide yes)
			)
		)
		(property "Val" "100n"
			(at 113.665 177.165 90)
			(effects
				(font
					(size 1.27 1.27)
					(thickness 0.15)
				)
				(justify left bottom)
			)
		)
		(property "License" "Apache-2.0"
			(at 90.17 191.77 0)
			(effects
				(font
					(size 1.27 1.27)
					(thickness 0.15)
				)
				(justify left bottom)
				(hide yes)
			)
		)
		(property "Author" "Antmicro"
			(at 87.63 191.77 0)
			(effects
				(font
					(size 1.27 1.27)
					(thickness 0.15)
				)
				(justify left bottom)
				(hide yes)
			)
		)
		(property "Voltage" ""
			(at 85.09 191.77 0)
			(effects
				(font
					(size 1.27 1.27)
				)
				(justify left bottom)
				(hide yes)
			)
		)
		(property "Dielectric" ""
			(at 82.55 191.77 0)
			(effects
				(font
					(size 1.27 1.27)
				)
				(justify left bottom)
				(hide yes)
			)
		)
		(pin "1"
		)
		(pin "2"
		)
		(instances
			(project "lpddr4-test-board"
				(path ""
					(reference "C47")
					(unit 1)
				)
			)
		)
	)
	(symbol
		(lib_id "antmicroCapacitorsmisc:C_100n_0201")
		(at 120.015 171.45 270)
		(unit 1)
		(exclude_from_sim no)
		(in_bom yes)
		(on_board yes)
		(dnp no)
		(property "Reference" "C51"
			(at 120.65 173.355 90)
			(effects
				(font
					(size 1.27 1.27)
					(thickness 0.15)
				)
				(justify left bottom)
			)
		)
		(property "Value" "C_100n_0201"
			(at 109.855 191.77 0)
			(effects
				(font
					(size 1.27 1.27)
					(thickness 0.15)
				)
				(justify left bottom)
				(hide yes)
			)
		)
		(property "Footprint" "antmicro-footprints:C_0201"
			(at 107.315 191.77 0)
			(effects
				(font
					(size 1.27 1.27)
					(thickness 0.15)
				)
				(justify left bottom)
				(hide yes)
			)
		)
		(property "Datasheet" " "
			(at 104.775 191.77 0)
			(effects
				(font
					(size 1.27 1.27)
					(thickness 0.15)
				)
				(justify left bottom)
				(hide yes)
			)
		)
		(property "Description" ""
			(at 120.015 171.45 0)
			(effects
				(font
					(size 1.27 1.27)
				)
			)
		)
		(property "Manufacturer" "Yaego"
			(at 99.695 191.77 0)
			(effects
				(font
					(size 1.27 1.27)
					(thickness 0.15)
				)
				(justify left bottom)
				(hide yes)
			)
		)
		(property "MPN" "CC0201KRX6S5BB104"
			(at 102.235 191.77 0)
			(effects
				(font
					(size 1.27 1.27)
					(thickness 0.15)
				)
				(justify left bottom)
				(hide yes)
			)
		)
		(property "Val" "100n"
			(at 120.65 177.165 90)
			(effects
				(font
					(size 1.27 1.27)
					(thickness 0.15)
				)
				(justify left bottom)
			)
		)
		(property "License" "Apache-2.0"
			(at 97.155 191.77 0)
			(effects
				(font
					(size 1.27 1.27)
					(thickness 0.15)
				)
				(justify left bottom)
				(hide yes)
			)
		)
		(property "Author" "Antmicro"
			(at 94.615 191.77 0)
			(effects
				(font
					(size 1.27 1.27)
					(thickness 0.15)
				)
				(justify left bottom)
				(hide yes)
			)
		)
		(property "Voltage" ""
			(at 92.075 191.77 0)
			(effects
				(font
					(size 1.27 1.27)
				)
				(justify left bottom)
				(hide yes)
			)
		)
		(property "Dielectric" ""
			(at 89.535 191.77 0)
			(effects
				(font
					(size 1.27 1.27)
				)
				(justify left bottom)
				(hide yes)
			)
		)
		(pin "1"
		)
		(pin "2"
		)
		(instances
			(project "lpddr4-test-board"
				(path ""
					(reference "C51")
					(unit 1)
				)
			)
		)
	)
	(symbol
		(lib_id "antmicroCapacitorsmisc:C_100n_0201")
		(at 127 171.45 270)
		(unit 1)
		(exclude_from_sim no)
		(in_bom yes)
		(on_board yes)
		(dnp no)
		(property "Reference" "C55"
			(at 127.635 173.355 90)
			(effects
				(font
					(size 1.27 1.27)
					(thickness 0.15)
				)
				(justify left bottom)
			)
		)
		(property "Value" "C_100n_0201"
			(at 116.84 191.77 0)
			(effects
				(font
					(size 1.27 1.27)
					(thickness 0.15)
				)
				(justify left bottom)
				(hide yes)
			)
		)
		(property "Footprint" "antmicro-footprints:C_0201"
			(at 114.3 191.77 0)
			(effects
				(font
					(size 1.27 1.27)
					(thickness 0.15)
				)
				(justify left bottom)
				(hide yes)
			)
		)
		(property "Datasheet" " "
			(at 111.76 191.77 0)
			(effects
				(font
					(size 1.27 1.27)
					(thickness 0.15)
				)
				(justify left bottom)
				(hide yes)
			)
		)
		(property "Description" ""
			(at 127 171.45 0)
			(effects
				(font
					(size 1.27 1.27)
				)
			)
		)
		(property "Manufacturer" "Yaego"
			(at 106.68 191.77 0)
			(effects
				(font
					(size 1.27 1.27)
					(thickness 0.15)
				)
				(justify left bottom)
				(hide yes)
			)
		)
		(property "MPN" "CC0201KRX6S5BB104"
			(at 109.22 191.77 0)
			(effects
				(font
					(size 1.27 1.27)
					(thickness 0.15)
				)
				(justify left bottom)
				(hide yes)
			)
		)
		(property "Val" "100n"
			(at 127.635 177.165 90)
			(effects
				(font
					(size 1.27 1.27)
					(thickness 0.15)
				)
				(justify left bottom)
			)
		)
		(property "License" "Apache-2.0"
			(at 104.14 191.77 0)
			(effects
				(font
					(size 1.27 1.27)
					(thickness 0.15)
				)
				(justify left bottom)
				(hide yes)
			)
		)
		(property "Author" "Antmicro"
			(at 101.6 191.77 0)
			(effects
				(font
					(size 1.27 1.27)
					(thickness 0.15)
				)
				(justify left bottom)
				(hide yes)
			)
		)
		(property "Voltage" ""
			(at 99.06 191.77 0)
			(effects
				(font
					(size 1.27 1.27)
				)
				(justify left bottom)
				(hide yes)
			)
		)
		(property "Dielectric" ""
			(at 96.52 191.77 0)
			(effects
				(font
					(size 1.27 1.27)
				)
				(justify left bottom)
				(hide yes)
			)
		)
		(pin "1"
		)
		(pin "2"
		)
		(instances
			(project "lpddr4-test-board"
				(path ""
					(reference "C55")
					(unit 1)
				)
			)
		)
	)
	(symbol
		(lib_id "antmicroCapacitorsmisc:C_100n_0201")
		(at 133.985 171.45 270)
		(unit 1)
		(exclude_from_sim no)
		(in_bom yes)
		(on_board yes)
		(dnp no)
		(property "Reference" "C61"
			(at 134.62 173.355 90)
			(effects
				(font
					(size 1.27 1.27)
					(thickness 0.15)
				)
				(justify left bottom)
			)
		)
		(property "Value" "C_100n_0201"
			(at 123.825 191.77 0)
			(effects
				(font
					(size 1.27 1.27)
					(thickness 0.15)
				)
				(justify left bottom)
				(hide yes)
			)
		)
		(property "Footprint" "antmicro-footprints:C_0201"
			(at 121.285 191.77 0)
			(effects
				(font
					(size 1.27 1.27)
					(thickness 0.15)
				)
				(justify left bottom)
				(hide yes)
			)
		)
		(property "Datasheet" " "
			(at 118.745 191.77 0)
			(effects
				(font
					(size 1.27 1.27)
					(thickness 0.15)
				)
				(justify left bottom)
				(hide yes)
			)
		)
		(property "Description" ""
			(at 133.985 171.45 0)
			(effects
				(font
					(size 1.27 1.27)
				)
			)
		)
		(property "Manufacturer" "Yaego"
			(at 113.665 191.77 0)
			(effects
				(font
					(size 1.27 1.27)
					(thickness 0.15)
				)
				(justify left bottom)
				(hide yes)
			)
		)
		(property "MPN" "CC0201KRX6S5BB104"
			(at 116.205 191.77 0)
			(effects
				(font
					(size 1.27 1.27)
					(thickness 0.15)
				)
				(justify left bottom)
				(hide yes)
			)
		)
		(property "Val" "100n"
			(at 134.62 177.165 90)
			(effects
				(font
					(size 1.27 1.27)
					(thickness 0.15)
				)
				(justify left bottom)
			)
		)
		(property "License" "Apache-2.0"
			(at 111.125 191.77 0)
			(effects
				(font
					(size 1.27 1.27)
					(thickness 0.15)
				)
				(justify left bottom)
				(hide yes)
			)
		)
		(property "Author" "Antmicro"
			(at 108.585 191.77 0)
			(effects
				(font
					(size 1.27 1.27)
					(thickness 0.15)
				)
				(justify left bottom)
				(hide yes)
			)
		)
		(property "Voltage" ""
			(at 106.045 191.77 0)
			(effects
				(font
					(size 1.27 1.27)
				)
				(justify left bottom)
				(hide yes)
			)
		)
		(property "Dielectric" ""
			(at 103.505 191.77 0)
			(effects
				(font
					(size 1.27 1.27)
				)
				(justify left bottom)
				(hide yes)
			)
		)
		(pin "1"
		)
		(pin "2"
		)
		(instances
			(project "lpddr4-test-board"
				(path ""
					(reference "C61")
					(unit 1)
				)
			)
		)
	)
	(symbol
		(lib_id "antmicroCapacitorsmisc:C_100n_0201")
		(at 140.97 171.45 270)
		(unit 1)
		(exclude_from_sim no)
		(in_bom yes)
		(on_board yes)
		(dnp no)
		(property "Reference" "C65"
			(at 141.605 173.355 90)
			(effects
				(font
					(size 1.27 1.27)
					(thickness 0.15)
				)
				(justify left bottom)
			)
		)
		(property "Value" "C_100n_0201"
			(at 130.81 191.77 0)
			(effects
				(font
					(size 1.27 1.27)
					(thickness 0.15)
				)
				(justify left bottom)
				(hide yes)
			)
		)
		(property "Footprint" "antmicro-footprints:C_0201"
			(at 128.27 191.77 0)
			(effects
				(font
					(size 1.27 1.27)
					(thickness 0.15)
				)
				(justify left bottom)
				(hide yes)
			)
		)
		(property "Datasheet" " "
			(at 125.73 191.77 0)
			(effects
				(font
					(size 1.27 1.27)
					(thickness 0.15)
				)
				(justify left bottom)
				(hide yes)
			)
		)
		(property "Description" ""
			(at 140.97 171.45 0)
			(effects
				(font
					(size 1.27 1.27)
				)
			)
		)
		(property "Manufacturer" "Yaego"
			(at 120.65 191.77 0)
			(effects
				(font
					(size 1.27 1.27)
					(thickness 0.15)
				)
				(justify left bottom)
				(hide yes)
			)
		)
		(property "MPN" "CC0201KRX6S5BB104"
			(at 123.19 191.77 0)
			(effects
				(font
					(size 1.27 1.27)
					(thickness 0.15)
				)
				(justify left bottom)
				(hide yes)
			)
		)
		(property "Val" "100n"
			(at 141.605 177.165 90)
			(effects
				(font
					(size 1.27 1.27)
					(thickness 0.15)
				)
				(justify left bottom)
			)
		)
		(property "License" "Apache-2.0"
			(at 118.11 191.77 0)
			(effects
				(font
					(size 1.27 1.27)
					(thickness 0.15)
				)
				(justify left bottom)
				(hide yes)
			)
		)
		(property "Author" "Antmicro"
			(at 115.57 191.77 0)
			(effects
				(font
					(size 1.27 1.27)
					(thickness 0.15)
				)
				(justify left bottom)
				(hide yes)
			)
		)
		(property "Voltage" ""
			(at 113.03 191.77 0)
			(effects
				(font
					(size 1.27 1.27)
				)
				(justify left bottom)
				(hide yes)
			)
		)
		(property "Dielectric" ""
			(at 110.49 191.77 0)
			(effects
				(font
					(size 1.27 1.27)
				)
				(justify left bottom)
				(hide yes)
			)
		)
		(pin "1"
		)
		(pin "2"
		)
		(instances
			(project "lpddr4-test-board"
				(path ""
					(reference "C65")
					(unit 1)
				)
			)
		)
	)
	(symbol
		(lib_id "antmicroCapacitorsmisc:C_100n_0201")
		(at 147.955 171.45 270)
		(unit 1)
		(exclude_from_sim no)
		(in_bom yes)
		(on_board yes)
		(dnp no)
		(property "Reference" "C69"
			(at 148.59 173.355 90)
			(effects
				(font
					(size 1.27 1.27)
					(thickness 0.15)
				)
				(justify left bottom)
			)
		)
		(property "Value" "C_100n_0201"
			(at 137.795 191.77 0)
			(effects
				(font
					(size 1.27 1.27)
					(thickness 0.15)
				)
				(justify left bottom)
				(hide yes)
			)
		)
		(property "Footprint" "antmicro-footprints:C_0201"
			(at 135.255 191.77 0)
			(effects
				(font
					(size 1.27 1.27)
					(thickness 0.15)
				)
				(justify left bottom)
				(hide yes)
			)
		)
		(property "Datasheet" " "
			(at 132.715 191.77 0)
			(effects
				(font
					(size 1.27 1.27)
					(thickness 0.15)
				)
				(justify left bottom)
				(hide yes)
			)
		)
		(property "Description" ""
			(at 147.955 171.45 0)
			(effects
				(font
					(size 1.27 1.27)
				)
			)
		)
		(property "Manufacturer" "Yaego"
			(at 127.635 191.77 0)
			(effects
				(font
					(size 1.27 1.27)
					(thickness 0.15)
				)
				(justify left bottom)
				(hide yes)
			)
		)
		(property "MPN" "CC0201KRX6S5BB104"
			(at 130.175 191.77 0)
			(effects
				(font
					(size 1.27 1.27)
					(thickness 0.15)
				)
				(justify left bottom)
				(hide yes)
			)
		)
		(property "Val" "100n"
			(at 148.59 177.165 90)
			(effects
				(font
					(size 1.27 1.27)
					(thickness 0.15)
				)
				(justify left bottom)
			)
		)
		(property "License" "Apache-2.0"
			(at 125.095 191.77 0)
			(effects
				(font
					(size 1.27 1.27)
					(thickness 0.15)
				)
				(justify left bottom)
				(hide yes)
			)
		)
		(property "Author" "Antmicro"
			(at 122.555 191.77 0)
			(effects
				(font
					(size 1.27 1.27)
					(thickness 0.15)
				)
				(justify left bottom)
				(hide yes)
			)
		)
		(property "Voltage" ""
			(at 120.015 191.77 0)
			(effects
				(font
					(size 1.27 1.27)
				)
				(justify left bottom)
				(hide yes)
			)
		)
		(property "Dielectric" ""
			(at 117.475 191.77 0)
			(effects
				(font
					(size 1.27 1.27)
				)
				(justify left bottom)
				(hide yes)
			)
		)
		(pin "1"
		)
		(pin "2"
		)
		(instances
			(project "lpddr4-test-board"
				(path ""
					(reference "C69")
					(unit 1)
				)
			)
		)
	)
	(symbol
		(lib_id "antmicroCapacitorsmisc:C_100n_0201")
		(at 154.94 171.45 270)
		(unit 1)
		(exclude_from_sim no)
		(in_bom yes)
		(on_board yes)
		(dnp no)
		(property "Reference" "C73"
			(at 155.575 173.355 90)
			(effects
				(font
					(size 1.27 1.27)
					(thickness 0.15)
				)
				(justify left bottom)
			)
		)
		(property "Value" "C_100n_0201"
			(at 144.78 191.77 0)
			(effects
				(font
					(size 1.27 1.27)
					(thickness 0.15)
				)
				(justify left bottom)
				(hide yes)
			)
		)
		(property "Footprint" "antmicro-footprints:C_0201"
			(at 142.24 191.77 0)
			(effects
				(font
					(size 1.27 1.27)
					(thickness 0.15)
				)
				(justify left bottom)
				(hide yes)
			)
		)
		(property "Datasheet" " "
			(at 139.7 191.77 0)
			(effects
				(font
					(size 1.27 1.27)
					(thickness 0.15)
				)
				(justify left bottom)
				(hide yes)
			)
		)
		(property "Description" ""
			(at 154.94 171.45 0)
			(effects
				(font
					(size 1.27 1.27)
				)
			)
		)
		(property "Manufacturer" "Yaego"
			(at 134.62 191.77 0)
			(effects
				(font
					(size 1.27 1.27)
					(thickness 0.15)
				)
				(justify left bottom)
				(hide yes)
			)
		)
		(property "MPN" "CC0201KRX6S5BB104"
			(at 137.16 191.77 0)
			(effects
				(font
					(size 1.27 1.27)
					(thickness 0.15)
				)
				(justify left bottom)
				(hide yes)
			)
		)
		(property "Val" "100n"
			(at 155.575 177.165 90)
			(effects
				(font
					(size 1.27 1.27)
					(thickness 0.15)
				)
				(justify left bottom)
			)
		)
		(property "License" "Apache-2.0"
			(at 132.08 191.77 0)
			(effects
				(font
					(size 1.27 1.27)
					(thickness 0.15)
				)
				(justify left bottom)
				(hide yes)
			)
		)
		(property "Author" "Antmicro"
			(at 129.54 191.77 0)
			(effects
				(font
					(size 1.27 1.27)
					(thickness 0.15)
				)
				(justify left bottom)
				(hide yes)
			)
		)
		(property "Voltage" ""
			(at 127 191.77 0)
			(effects
				(font
					(size 1.27 1.27)
				)
				(justify left bottom)
				(hide yes)
			)
		)
		(property "Dielectric" ""
			(at 124.46 191.77 0)
			(effects
				(font
					(size 1.27 1.27)
				)
				(justify left bottom)
				(hide yes)
			)
		)
		(pin "1"
		)
		(pin "2"
		)
		(instances
			(project "lpddr4-test-board"
				(path ""
					(reference "C73")
					(unit 1)
				)
			)
		)
	)
	(symbol
		(lib_id "antmicroCapacitorsmisc:C_100n_0201")
		(at 189.865 95.25 270)
		(unit 1)
		(exclude_from_sim no)
		(in_bom yes)
		(on_board yes)
		(dnp no)
		(property "Reference" "C78"
			(at 190.5 97.155 90)
			(effects
				(font
					(size 1.27 1.27)
					(thickness 0.15)
				)
				(justify left bottom)
			)
		)
		(property "Value" "C_100n_0201"
			(at 179.705 115.57 0)
			(effects
				(font
					(size 1.27 1.27)
					(thickness 0.15)
				)
				(justify left bottom)
				(hide yes)
			)
		)
		(property "Footprint" "antmicro-footprints:C_0201"
			(at 177.165 115.57 0)
			(effects
				(font
					(size 1.27 1.27)
					(thickness 0.15)
				)
				(justify left bottom)
				(hide yes)
			)
		)
		(property "Datasheet" " "
			(at 174.625 115.57 0)
			(effects
				(font
					(size 1.27 1.27)
					(thickness 0.15)
				)
				(justify left bottom)
				(hide yes)
			)
		)
		(property "Description" ""
			(at 189.865 95.25 0)
			(effects
				(font
					(size 1.27 1.27)
				)
			)
		)
		(property "Manufacturer" "Yaego"
			(at 169.545 115.57 0)
			(effects
				(font
					(size 1.27 1.27)
					(thickness 0.15)
				)
				(justify left bottom)
				(hide yes)
			)
		)
		(property "MPN" "CC0201KRX6S5BB104"
			(at 172.085 115.57 0)
			(effects
				(font
					(size 1.27 1.27)
					(thickness 0.15)
				)
				(justify left bottom)
				(hide yes)
			)
		)
		(property "Val" "100n"
			(at 190.5 100.965 90)
			(effects
				(font
					(size 1.27 1.27)
					(thickness 0.15)
				)
				(justify left bottom)
			)
		)
		(property "License" "Apache-2.0"
			(at 167.005 115.57 0)
			(effects
				(font
					(size 1.27 1.27)
					(thickness 0.15)
				)
				(justify left bottom)
				(hide yes)
			)
		)
		(property "Author" "Antmicro"
			(at 164.465 115.57 0)
			(effects
				(font
					(size 1.27 1.27)
					(thickness 0.15)
				)
				(justify left bottom)
				(hide yes)
			)
		)
		(property "Voltage" ""
			(at 161.925 115.57 0)
			(effects
				(font
					(size 1.27 1.27)
				)
				(justify left bottom)
				(hide yes)
			)
		)
		(property "Dielectric" ""
			(at 159.385 115.57 0)
			(effects
				(font
					(size 1.27 1.27)
				)
				(justify left bottom)
				(hide yes)
			)
		)
		(pin "1"
		)
		(pin "2"
		)
		(instances
			(project "lpddr4-test-board"
				(path ""
					(reference "C78")
					(unit 1)
				)
			)
		)
	)
	(symbol
		(lib_id "antmicropower:GND")
		(at 120.015 101.6 0)
		(unit 1)
		(exclude_from_sim no)
		(in_bom yes)
		(on_board yes)
		(dnp no)
		(property "Reference" "#PWR0112"
			(at 128.905 104.14 0)
			(effects
				(font
					(size 1.27 1.27)
					(thickness 0.15)
				)
				(justify left bottom)
				(hide yes)
			)
		)
		(property "Value" "GND"
			(at 118.11 106.045 0)
			(effects
				(font
					(size 1.27 1.27)
					(thickness 0.15)
				)
				(justify left bottom)
			)
		)
		(property "Footprint" ""
			(at 128.905 109.22 0)
			(effects
				(font
					(size 1.27 1.27)
					(thickness 0.15)
				)
				(justify left bottom)
				(hide yes)
			)
		)
		(property "Datasheet" ""
			(at 128.905 114.3 0)
			(effects
				(font
					(size 1.27 1.27)
					(thickness 0.15)
				)
				(justify left bottom)
				(hide yes)
			)
		)
		(property "Description" ""
			(at 120.015 101.6 0)
			(effects
				(font
					(size 1.27 1.27)
				)
			)
		)
		(property "Author" "Antmicro"
			(at 128.905 109.22 0)
			(effects
				(font
					(size 1.27 1.27)
					(thickness 0.15)
				)
				(justify left bottom)
				(hide yes)
			)
		)
		(property "License" "Apache-2.0"
			(at 128.905 111.76 0)
			(effects
				(font
					(size 1.27 1.27)
					(thickness 0.15)
				)
				(justify left bottom)
				(hide yes)
			)
		)
		(pin "1"
		)
		(instances
			(project "lpddr4-test-board"
				(path ""
					(reference "#PWR0112")
					(unit 1)
				)
			)
		)
	)
	(symbol
		(lib_id "antmicroCapacitors0402:C_4u7_0402")
		(at 92.075 228.6 270)
		(unit 1)
		(exclude_from_sim no)
		(in_bom yes)
		(on_board yes)
		(dnp no)
		(property "Reference" "C28"
			(at 92.71 230.505 90)
			(effects
				(font
					(size 1.27 1.27)
					(thickness 0.15)
				)
				(justify left bottom)
			)
		)
		(property "Value" "C_4u7_0402"
			(at 81.915 248.92 0)
			(effects
				(font
					(size 1.27 1.27)
					(thickness 0.15)
				)
				(justify left bottom)
				(hide yes)
			)
		)
		(property "Footprint" "antmicro-footprints:C_0402_1005Metric"
			(at 79.375 248.92 0)
			(effects
				(font
					(size 1.27 1.27)
					(thickness 0.15)
				)
				(justify left bottom)
				(hide yes)
			)
		)
		(property "Datasheet" " "
			(at 76.835 248.92 0)
			(effects
				(font
					(size 1.27 1.27)
					(thickness 0.15)
				)
				(justify left bottom)
				(hide yes)
			)
		)
		(property "Description" ""
			(at 92.075 228.6 0)
			(effects
				(font
					(size 1.27 1.27)
				)
			)
		)
		(property "Manufacturer" "Murata"
			(at 71.755 248.92 0)
			(effects
				(font
					(size 1.27 1.27)
					(thickness 0.15)
				)
				(justify left bottom)
				(hide yes)
			)
		)
		(property "MPN" "GRM155R61A475MEAAD"
			(at 74.295 248.92 0)
			(effects
				(font
					(size 1.27 1.27)
					(thickness 0.15)
				)
				(justify left bottom)
				(hide yes)
			)
		)
		(property "Val" "4u7"
			(at 92.71 234.315 90)
			(effects
				(font
					(size 1.27 1.27)
					(thickness 0.15)
				)
				(justify left bottom)
			)
		)
		(property "License" "Apache-2.0"
			(at 69.215 248.92 0)
			(effects
				(font
					(size 1.27 1.27)
					(thickness 0.15)
				)
				(justify left bottom)
				(hide yes)
			)
		)
		(property "Author" "Antmicro"
			(at 66.675 248.92 0)
			(effects
				(font
					(size 1.27 1.27)
					(thickness 0.15)
				)
				(justify left bottom)
				(hide yes)
			)
		)
		(property "Voltage" ""
			(at 64.135 248.92 0)
			(effects
				(font
					(size 1.27 1.27)
				)
				(justify left bottom)
				(hide yes)
			)
		)
		(property "Dielectric" ""
			(at 61.595 248.92 0)
			(effects
				(font
					(size 1.27 1.27)
				)
				(justify left bottom)
				(hide yes)
			)
		)
		(pin "1"
		)
		(pin "2"
		)
		(instances
			(project "lpddr4-test-board"
				(path ""
					(reference "C28")
					(unit 1)
				)
			)
		)
	)
	(symbol
		(lib_id "antmicroCapacitors0402:C_4u7_0402")
		(at 99.06 228.6 270)
		(unit 1)
		(exclude_from_sim no)
		(in_bom yes)
		(on_board yes)
		(dnp no)
		(property "Reference" "C32"
			(at 99.695 230.505 90)
			(effects
				(font
					(size 1.27 1.27)
					(thickness 0.15)
				)
				(justify left bottom)
			)
		)
		(property "Value" "C_4u7_0402"
			(at 88.9 248.92 0)
			(effects
				(font
					(size 1.27 1.27)
					(thickness 0.15)
				)
				(justify left bottom)
				(hide yes)
			)
		)
		(property "Footprint" "antmicro-footprints:C_0402_1005Metric"
			(at 86.36 248.92 0)
			(effects
				(font
					(size 1.27 1.27)
					(thickness 0.15)
				)
				(justify left bottom)
				(hide yes)
			)
		)
		(property "Datasheet" " "
			(at 83.82 248.92 0)
			(effects
				(font
					(size 1.27 1.27)
					(thickness 0.15)
				)
				(justify left bottom)
				(hide yes)
			)
		)
		(property "Description" ""
			(at 99.06 228.6 0)
			(effects
				(font
					(size 1.27 1.27)
				)
			)
		)
		(property "Manufacturer" "Murata"
			(at 78.74 248.92 0)
			(effects
				(font
					(size 1.27 1.27)
					(thickness 0.15)
				)
				(justify left bottom)
				(hide yes)
			)
		)
		(property "MPN" "GRM155R61A475MEAAD"
			(at 81.28 248.92 0)
			(effects
				(font
					(size 1.27 1.27)
					(thickness 0.15)
				)
				(justify left bottom)
				(hide yes)
			)
		)
		(property "Val" "4u7"
			(at 99.695 234.315 90)
			(effects
				(font
					(size 1.27 1.27)
					(thickness 0.15)
				)
				(justify left bottom)
			)
		)
		(property "License" "Apache-2.0"
			(at 76.2 248.92 0)
			(effects
				(font
					(size 1.27 1.27)
					(thickness 0.15)
				)
				(justify left bottom)
				(hide yes)
			)
		)
		(property "Author" "Antmicro"
			(at 73.66 248.92 0)
			(effects
				(font
					(size 1.27 1.27)
					(thickness 0.15)
				)
				(justify left bottom)
				(hide yes)
			)
		)
		(property "Voltage" ""
			(at 71.12 248.92 0)
			(effects
				(font
					(size 1.27 1.27)
				)
				(justify left bottom)
				(hide yes)
			)
		)
		(property "Dielectric" ""
			(at 68.58 248.92 0)
			(effects
				(font
					(size 1.27 1.27)
				)
				(justify left bottom)
				(hide yes)
			)
		)
		(pin "1"
		)
		(pin "2"
		)
		(instances
			(project "lpddr4-test-board"
				(path ""
					(reference "C32")
					(unit 1)
				)
			)
		)
	)
	(symbol
		(lib_id "antmicroCapacitors0402:C_4u7_0402")
		(at 106.045 228.6 270)
		(unit 1)
		(exclude_from_sim no)
		(in_bom yes)
		(on_board yes)
		(dnp no)
		(property "Reference" "C36"
			(at 106.68 230.505 90)
			(effects
				(font
					(size 1.27 1.27)
					(thickness 0.15)
				)
				(justify left bottom)
			)
		)
		(property "Value" "C_4u7_0402"
			(at 95.885 248.92 0)
			(effects
				(font
					(size 1.27 1.27)
					(thickness 0.15)
				)
				(justify left bottom)
				(hide yes)
			)
		)
		(property "Footprint" "antmicro-footprints:C_0402_1005Metric"
			(at 93.345 248.92 0)
			(effects
				(font
					(size 1.27 1.27)
					(thickness 0.15)
				)
				(justify left bottom)
				(hide yes)
			)
		)
		(property "Datasheet" " "
			(at 90.805 248.92 0)
			(effects
				(font
					(size 1.27 1.27)
					(thickness 0.15)
				)
				(justify left bottom)
				(hide yes)
			)
		)
		(property "Description" ""
			(at 106.045 228.6 0)
			(effects
				(font
					(size 1.27 1.27)
				)
			)
		)
		(property "Manufacturer" "Murata"
			(at 85.725 248.92 0)
			(effects
				(font
					(size 1.27 1.27)
					(thickness 0.15)
				)
				(justify left bottom)
				(hide yes)
			)
		)
		(property "MPN" "GRM155R61A475MEAAD"
			(at 88.265 248.92 0)
			(effects
				(font
					(size 1.27 1.27)
					(thickness 0.15)
				)
				(justify left bottom)
				(hide yes)
			)
		)
		(property "Val" "4u7"
			(at 106.68 234.315 90)
			(effects
				(font
					(size 1.27 1.27)
					(thickness 0.15)
				)
				(justify left bottom)
			)
		)
		(property "License" "Apache-2.0"
			(at 83.185 248.92 0)
			(effects
				(font
					(size 1.27 1.27)
					(thickness 0.15)
				)
				(justify left bottom)
				(hide yes)
			)
		)
		(property "Author" "Antmicro"
			(at 80.645 248.92 0)
			(effects
				(font
					(size 1.27 1.27)
					(thickness 0.15)
				)
				(justify left bottom)
				(hide yes)
			)
		)
		(property "Voltage" ""
			(at 78.105 248.92 0)
			(effects
				(font
					(size 1.27 1.27)
				)
				(justify left bottom)
				(hide yes)
			)
		)
		(property "Dielectric" ""
			(at 75.565 248.92 0)
			(effects
				(font
					(size 1.27 1.27)
				)
				(justify left bottom)
				(hide yes)
			)
		)
		(pin "1"
		)
		(pin "2"
		)
		(instances
			(project "lpddr4-test-board"
				(path ""
					(reference "C36")
					(unit 1)
				)
			)
		)
	)
	(symbol
		(lib_id "antmicroCapacitors0402:C_4u7_0402")
		(at 113.03 228.6 270)
		(unit 1)
		(exclude_from_sim no)
		(in_bom yes)
		(on_board yes)
		(dnp no)
		(property "Reference" "C40"
			(at 113.665 230.505 90)
			(effects
				(font
					(size 1.27 1.27)
					(thickness 0.15)
				)
				(justify left bottom)
			)
		)
		(property "Value" "C_4u7_0402"
			(at 102.87 248.92 0)
			(effects
				(font
					(size 1.27 1.27)
					(thickness 0.15)
				)
				(justify left bottom)
				(hide yes)
			)
		)
		(property "Footprint" "antmicro-footprints:C_0402_1005Metric"
			(at 100.33 248.92 0)
			(effects
				(font
					(size 1.27 1.27)
					(thickness 0.15)
				)
				(justify left bottom)
				(hide yes)
			)
		)
		(property "Datasheet" " "
			(at 97.79 248.92 0)
			(effects
				(font
					(size 1.27 1.27)
					(thickness 0.15)
				)
				(justify left bottom)
				(hide yes)
			)
		)
		(property "Description" ""
			(at 113.03 228.6 0)
			(effects
				(font
					(size 1.27 1.27)
				)
			)
		)
		(property "Manufacturer" "Murata"
			(at 92.71 248.92 0)
			(effects
				(font
					(size 1.27 1.27)
					(thickness 0.15)
				)
				(justify left bottom)
				(hide yes)
			)
		)
		(property "MPN" "GRM155R61A475MEAAD"
			(at 95.25 248.92 0)
			(effects
				(font
					(size 1.27 1.27)
					(thickness 0.15)
				)
				(justify left bottom)
				(hide yes)
			)
		)
		(property "Val" "4u7"
			(at 113.665 234.315 90)
			(effects
				(font
					(size 1.27 1.27)
					(thickness 0.15)
				)
				(justify left bottom)
			)
		)
		(property "License" "Apache-2.0"
			(at 90.17 248.92 0)
			(effects
				(font
					(size 1.27 1.27)
					(thickness 0.15)
				)
				(justify left bottom)
				(hide yes)
			)
		)
		(property "Author" "Antmicro"
			(at 87.63 248.92 0)
			(effects
				(font
					(size 1.27 1.27)
					(thickness 0.15)
				)
				(justify left bottom)
				(hide yes)
			)
		)
		(property "Voltage" ""
			(at 85.09 248.92 0)
			(effects
				(font
					(size 1.27 1.27)
				)
				(justify left bottom)
				(hide yes)
			)
		)
		(property "Dielectric" ""
			(at 82.55 248.92 0)
			(effects
				(font
					(size 1.27 1.27)
				)
				(justify left bottom)
				(hide yes)
			)
		)
		(pin "1"
		)
		(pin "2"
		)
		(instances
			(project "lpddr4-test-board"
				(path ""
					(reference "C40")
					(unit 1)
				)
			)
		)
	)
	(symbol
		(lib_id "antmicroCapacitors0402:C_4u7_0402")
		(at 120.015 228.6 270)
		(unit 1)
		(exclude_from_sim no)
		(in_bom yes)
		(on_board yes)
		(dnp no)
		(property "Reference" "C46"
			(at 120.65 230.505 90)
			(effects
				(font
					(size 1.27 1.27)
					(thickness 0.15)
				)
				(justify left bottom)
			)
		)
		(property "Value" "C_4u7_0402"
			(at 109.855 248.92 0)
			(effects
				(font
					(size 1.27 1.27)
					(thickness 0.15)
				)
				(justify left bottom)
				(hide yes)
			)
		)
		(property "Footprint" "antmicro-footprints:C_0402_1005Metric"
			(at 107.315 248.92 0)
			(effects
				(font
					(size 1.27 1.27)
					(thickness 0.15)
				)
				(justify left bottom)
				(hide yes)
			)
		)
		(property "Datasheet" " "
			(at 104.775 248.92 0)
			(effects
				(font
					(size 1.27 1.27)
					(thickness 0.15)
				)
				(justify left bottom)
				(hide yes)
			)
		)
		(property "Description" ""
			(at 120.015 228.6 0)
			(effects
				(font
					(size 1.27 1.27)
				)
			)
		)
		(property "Manufacturer" "Murata"
			(at 99.695 248.92 0)
			(effects
				(font
					(size 1.27 1.27)
					(thickness 0.15)
				)
				(justify left bottom)
				(hide yes)
			)
		)
		(property "MPN" "GRM155R61A475MEAAD"
			(at 102.235 248.92 0)
			(effects
				(font
					(size 1.27 1.27)
					(thickness 0.15)
				)
				(justify left bottom)
				(hide yes)
			)
		)
		(property "Val" "4u7"
			(at 120.65 234.315 90)
			(effects
				(font
					(size 1.27 1.27)
					(thickness 0.15)
				)
				(justify left bottom)
			)
		)
		(property "License" "Apache-2.0"
			(at 97.155 248.92 0)
			(effects
				(font
					(size 1.27 1.27)
					(thickness 0.15)
				)
				(justify left bottom)
				(hide yes)
			)
		)
		(property "Author" "Antmicro"
			(at 94.615 248.92 0)
			(effects
				(font
					(size 1.27 1.27)
					(thickness 0.15)
				)
				(justify left bottom)
				(hide yes)
			)
		)
		(property "Voltage" ""
			(at 92.075 248.92 0)
			(effects
				(font
					(size 1.27 1.27)
				)
				(justify left bottom)
				(hide yes)
			)
		)
		(property "Dielectric" ""
			(at 89.535 248.92 0)
			(effects
				(font
					(size 1.27 1.27)
				)
				(justify left bottom)
				(hide yes)
			)
		)
		(pin "1"
		)
		(pin "2"
		)
		(instances
			(project "lpddr4-test-board"
				(path ""
					(reference "C46")
					(unit 1)
				)
			)
		)
	)
	(symbol
		(lib_id "antmicroCapacitors0402:C_4u7_0402")
		(at 127 228.6 270)
		(unit 1)
		(exclude_from_sim no)
		(in_bom yes)
		(on_board yes)
		(dnp no)
		(property "Reference" "C50"
			(at 128.27 230.505 90)
			(effects
				(font
					(size 1.27 1.27)
					(thickness 0.15)
				)
				(justify left bottom)
			)
		)
		(property "Value" "C_4u7_0402"
			(at 116.84 248.92 0)
			(effects
				(font
					(size 1.27 1.27)
					(thickness 0.15)
				)
				(justify left bottom)
				(hide yes)
			)
		)
		(property "Footprint" "antmicro-footprints:C_0402_1005Metric"
			(at 114.3 248.92 0)
			(effects
				(font
					(size 1.27 1.27)
					(thickness 0.15)
				)
				(justify left bottom)
				(hide yes)
			)
		)
		(property "Datasheet" " "
			(at 111.76 248.92 0)
			(effects
				(font
					(size 1.27 1.27)
					(thickness 0.15)
				)
				(justify left bottom)
				(hide yes)
			)
		)
		(property "Description" ""
			(at 127 228.6 0)
			(effects
				(font
					(size 1.27 1.27)
				)
			)
		)
		(property "Manufacturer" "Murata"
			(at 106.68 248.92 0)
			(effects
				(font
					(size 1.27 1.27)
					(thickness 0.15)
				)
				(justify left bottom)
				(hide yes)
			)
		)
		(property "MPN" "GRM155R61A475MEAAD"
			(at 109.22 248.92 0)
			(effects
				(font
					(size 1.27 1.27)
					(thickness 0.15)
				)
				(justify left bottom)
				(hide yes)
			)
		)
		(property "Val" "4u7"
			(at 128.27 234.315 90)
			(effects
				(font
					(size 1.27 1.27)
					(thickness 0.15)
				)
				(justify left bottom)
			)
		)
		(property "License" "Apache-2.0"
			(at 104.14 248.92 0)
			(effects
				(font
					(size 1.27 1.27)
					(thickness 0.15)
				)
				(justify left bottom)
				(hide yes)
			)
		)
		(property "Author" "Antmicro"
			(at 101.6 248.92 0)
			(effects
				(font
					(size 1.27 1.27)
					(thickness 0.15)
				)
				(justify left bottom)
				(hide yes)
			)
		)
		(property "Voltage" ""
			(at 99.06 248.92 0)
			(effects
				(font
					(size 1.27 1.27)
				)
				(justify left bottom)
				(hide yes)
			)
		)
		(property "Dielectric" ""
			(at 96.52 248.92 0)
			(effects
				(font
					(size 1.27 1.27)
				)
				(justify left bottom)
				(hide yes)
			)
		)
		(pin "1"
		)
		(pin "2"
		)
		(instances
			(project "lpddr4-test-board"
				(path ""
					(reference "C50")
					(unit 1)
				)
			)
		)
	)
	(symbol
		(lib_id "antmicroCapacitors0402:C_4u7_0402")
		(at 133.985 228.6 270)
		(unit 1)
		(exclude_from_sim no)
		(in_bom yes)
		(on_board yes)
		(dnp no)
		(property "Reference" "C54"
			(at 134.62 230.505 90)
			(effects
				(font
					(size 1.27 1.27)
					(thickness 0.15)
				)
				(justify left bottom)
			)
		)
		(property "Value" "C_4u7_0402"
			(at 123.825 248.92 0)
			(effects
				(font
					(size 1.27 1.27)
					(thickness 0.15)
				)
				(justify left bottom)
				(hide yes)
			)
		)
		(property "Footprint" "antmicro-footprints:C_0402_1005Metric"
			(at 121.285 248.92 0)
			(effects
				(font
					(size 1.27 1.27)
					(thickness 0.15)
				)
				(justify left bottom)
				(hide yes)
			)
		)
		(property "Datasheet" " "
			(at 118.745 248.92 0)
			(effects
				(font
					(size 1.27 1.27)
					(thickness 0.15)
				)
				(justify left bottom)
				(hide yes)
			)
		)
		(property "Description" ""
			(at 133.985 228.6 0)
			(effects
				(font
					(size 1.27 1.27)
				)
			)
		)
		(property "Manufacturer" "Murata"
			(at 113.665 248.92 0)
			(effects
				(font
					(size 1.27 1.27)
					(thickness 0.15)
				)
				(justify left bottom)
				(hide yes)
			)
		)
		(property "MPN" "GRM155R61A475MEAAD"
			(at 116.205 248.92 0)
			(effects
				(font
					(size 1.27 1.27)
					(thickness 0.15)
				)
				(justify left bottom)
				(hide yes)
			)
		)
		(property "Val" "4u7"
			(at 134.62 234.315 90)
			(effects
				(font
					(size 1.27 1.27)
					(thickness 0.15)
				)
				(justify left bottom)
			)
		)
		(property "License" "Apache-2.0"
			(at 111.125 248.92 0)
			(effects
				(font
					(size 1.27 1.27)
					(thickness 0.15)
				)
				(justify left bottom)
				(hide yes)
			)
		)
		(property "Author" "Antmicro"
			(at 108.585 248.92 0)
			(effects
				(font
					(size 1.27 1.27)
					(thickness 0.15)
				)
				(justify left bottom)
				(hide yes)
			)
		)
		(property "Voltage" ""
			(at 106.045 248.92 0)
			(effects
				(font
					(size 1.27 1.27)
				)
				(justify left bottom)
				(hide yes)
			)
		)
		(property "Dielectric" ""
			(at 103.505 248.92 0)
			(effects
				(font
					(size 1.27 1.27)
				)
				(justify left bottom)
				(hide yes)
			)
		)
		(pin "1"
		)
		(pin "2"
		)
		(instances
			(project "lpddr4-test-board"
				(path ""
					(reference "C54")
					(unit 1)
				)
			)
		)
	)
	(symbol
		(lib_id "antmicroCapacitors0402:C_4u7_0402")
		(at 140.97 228.6 270)
		(unit 1)
		(exclude_from_sim no)
		(in_bom yes)
		(on_board yes)
		(dnp no)
		(property "Reference" "C58"
			(at 141.605 230.505 90)
			(effects
				(font
					(size 1.27 1.27)
					(thickness 0.15)
				)
				(justify left bottom)
			)
		)
		(property "Value" "C_4u7_0402"
			(at 130.81 248.92 0)
			(effects
				(font
					(size 1.27 1.27)
					(thickness 0.15)
				)
				(justify left bottom)
				(hide yes)
			)
		)
		(property "Footprint" "antmicro-footprints:C_0402_1005Metric"
			(at 128.27 248.92 0)
			(effects
				(font
					(size 1.27 1.27)
					(thickness 0.15)
				)
				(justify left bottom)
				(hide yes)
			)
		)
		(property "Datasheet" " "
			(at 125.73 248.92 0)
			(effects
				(font
					(size 1.27 1.27)
					(thickness 0.15)
				)
				(justify left bottom)
				(hide yes)
			)
		)
		(property "Description" ""
			(at 140.97 228.6 0)
			(effects
				(font
					(size 1.27 1.27)
				)
			)
		)
		(property "Manufacturer" "Murata"
			(at 120.65 248.92 0)
			(effects
				(font
					(size 1.27 1.27)
					(thickness 0.15)
				)
				(justify left bottom)
				(hide yes)
			)
		)
		(property "MPN" "GRM155R61A475MEAAD"
			(at 123.19 248.92 0)
			(effects
				(font
					(size 1.27 1.27)
					(thickness 0.15)
				)
				(justify left bottom)
				(hide yes)
			)
		)
		(property "Val" "4u7"
			(at 141.605 234.315 90)
			(effects
				(font
					(size 1.27 1.27)
					(thickness 0.15)
				)
				(justify left bottom)
			)
		)
		(property "License" "Apache-2.0"
			(at 118.11 248.92 0)
			(effects
				(font
					(size 1.27 1.27)
					(thickness 0.15)
				)
				(justify left bottom)
				(hide yes)
			)
		)
		(property "Author" "Antmicro"
			(at 115.57 248.92 0)
			(effects
				(font
					(size 1.27 1.27)
					(thickness 0.15)
				)
				(justify left bottom)
				(hide yes)
			)
		)
		(property "Voltage" ""
			(at 113.03 248.92 0)
			(effects
				(font
					(size 1.27 1.27)
				)
				(justify left bottom)
				(hide yes)
			)
		)
		(property "Dielectric" ""
			(at 110.49 248.92 0)
			(effects
				(font
					(size 1.27 1.27)
				)
				(justify left bottom)
				(hide yes)
			)
		)
		(pin "1"
		)
		(pin "2"
		)
		(instances
			(project "lpddr4-test-board"
				(path ""
					(reference "C58")
					(unit 1)
				)
			)
		)
	)
	(symbol
		(lib_id "antmicroCapacitors0402:C_4u7_0402")
		(at 147.955 228.6 270)
		(unit 1)
		(exclude_from_sim no)
		(in_bom yes)
		(on_board yes)
		(dnp no)
		(property "Reference" "C64"
			(at 148.59 230.505 90)
			(effects
				(font
					(size 1.27 1.27)
					(thickness 0.15)
				)
				(justify left bottom)
			)
		)
		(property "Value" "C_4u7_0402"
			(at 137.795 248.92 0)
			(effects
				(font
					(size 1.27 1.27)
					(thickness 0.15)
				)
				(justify left bottom)
				(hide yes)
			)
		)
		(property "Footprint" "antmicro-footprints:C_0402_1005Metric"
			(at 135.255 248.92 0)
			(effects
				(font
					(size 1.27 1.27)
					(thickness 0.15)
				)
				(justify left bottom)
				(hide yes)
			)
		)
		(property "Datasheet" " "
			(at 132.715 248.92 0)
			(effects
				(font
					(size 1.27 1.27)
					(thickness 0.15)
				)
				(justify left bottom)
				(hide yes)
			)
		)
		(property "Description" ""
			(at 147.955 228.6 0)
			(effects
				(font
					(size 1.27 1.27)
				)
			)
		)
		(property "Manufacturer" "Murata"
			(at 127.635 248.92 0)
			(effects
				(font
					(size 1.27 1.27)
					(thickness 0.15)
				)
				(justify left bottom)
				(hide yes)
			)
		)
		(property "MPN" "GRM155R61A475MEAAD"
			(at 130.175 248.92 0)
			(effects
				(font
					(size 1.27 1.27)
					(thickness 0.15)
				)
				(justify left bottom)
				(hide yes)
			)
		)
		(property "Val" "4u7"
			(at 148.59 234.315 90)
			(effects
				(font
					(size 1.27 1.27)
					(thickness 0.15)
				)
				(justify left bottom)
			)
		)
		(property "License" "Apache-2.0"
			(at 125.095 248.92 0)
			(effects
				(font
					(size 1.27 1.27)
					(thickness 0.15)
				)
				(justify left bottom)
				(hide yes)
			)
		)
		(property "Author" "Antmicro"
			(at 122.555 248.92 0)
			(effects
				(font
					(size 1.27 1.27)
					(thickness 0.15)
				)
				(justify left bottom)
				(hide yes)
			)
		)
		(property "Voltage" ""
			(at 120.015 248.92 0)
			(effects
				(font
					(size 1.27 1.27)
				)
				(justify left bottom)
				(hide yes)
			)
		)
		(property "Dielectric" ""
			(at 117.475 248.92 0)
			(effects
				(font
					(size 1.27 1.27)
				)
				(justify left bottom)
				(hide yes)
			)
		)
		(pin "1"
		)
		(pin "2"
		)
		(instances
			(project "lpddr4-test-board"
				(path ""
					(reference "C64")
					(unit 1)
				)
			)
		)
	)
	(symbol
		(lib_id "antmicroCapacitorsmisc:C_100n_0201")
		(at 92.075 133.35 270)
		(unit 1)
		(exclude_from_sim no)
		(in_bom yes)
		(on_board yes)
		(dnp no)
		(property "Reference" "C45"
			(at 92.71 135.255 90)
			(effects
				(font
					(size 1.27 1.27)
					(thickness 0.15)
				)
				(justify left bottom)
			)
		)
		(property "Value" "C_100n_0201"
			(at 81.915 153.67 0)
			(effects
				(font
					(size 1.27 1.27)
					(thickness 0.15)
				)
				(justify left bottom)
				(hide yes)
			)
		)
		(property "Footprint" "antmicro-footprints:C_0201"
			(at 79.375 153.67 0)
			(effects
				(font
					(size 1.27 1.27)
					(thickness 0.15)
				)
				(justify left bottom)
				(hide yes)
			)
		)
		(property "Datasheet" " "
			(at 76.835 153.67 0)
			(effects
				(font
					(size 1.27 1.27)
					(thickness 0.15)
				)
				(justify left bottom)
				(hide yes)
			)
		)
		(property "Description" ""
			(at 92.075 133.35 0)
			(effects
				(font
					(size 1.27 1.27)
				)
			)
		)
		(property "Manufacturer" "Yaego"
			(at 71.755 153.67 0)
			(effects
				(font
					(size 1.27 1.27)
					(thickness 0.15)
				)
				(justify left bottom)
				(hide yes)
			)
		)
		(property "MPN" "CC0201KRX6S5BB104"
			(at 74.295 153.67 0)
			(effects
				(font
					(size 1.27 1.27)
					(thickness 0.15)
				)
				(justify left bottom)
				(hide yes)
			)
		)
		(property "Val" "100n"
			(at 92.71 139.065 90)
			(effects
				(font
					(size 1.27 1.27)
					(thickness 0.15)
				)
				(justify left bottom)
			)
		)
		(property "License" "Apache-2.0"
			(at 69.215 153.67 0)
			(effects
				(font
					(size 1.27 1.27)
					(thickness 0.15)
				)
				(justify left bottom)
				(hide yes)
			)
		)
		(property "Author" "Antmicro"
			(at 66.675 153.67 0)
			(effects
				(font
					(size 1.27 1.27)
					(thickness 0.15)
				)
				(justify left bottom)
				(hide yes)
			)
		)
		(property "Voltage" ""
			(at 64.135 153.67 0)
			(effects
				(font
					(size 1.27 1.27)
				)
				(justify left bottom)
				(hide yes)
			)
		)
		(property "Dielectric" ""
			(at 61.595 153.67 0)
			(effects
				(font
					(size 1.27 1.27)
				)
				(justify left bottom)
				(hide yes)
			)
		)
		(pin "1"
		)
		(pin "2"
		)
		(instances
			(project "lpddr4-test-board"
				(path ""
					(reference "C45")
					(unit 1)
				)
			)
		)
	)
	(symbol
		(lib_id "antmicroCapacitors0402:C_4u7_0402")
		(at 154.94 228.6 270)
		(unit 1)
		(exclude_from_sim no)
		(in_bom yes)
		(on_board yes)
		(dnp no)
		(property "Reference" "C68"
			(at 155.575 230.505 90)
			(effects
				(font
					(size 1.27 1.27)
					(thickness 0.15)
				)
				(justify left bottom)
			)
		)
		(property "Value" "C_4u7_0402"
			(at 144.78 248.92 0)
			(effects
				(font
					(size 1.27 1.27)
					(thickness 0.15)
				)
				(justify left bottom)
				(hide yes)
			)
		)
		(property "Footprint" "antmicro-footprints:C_0402_1005Metric"
			(at 142.24 248.92 0)
			(effects
				(font
					(size 1.27 1.27)
					(thickness 0.15)
				)
				(justify left bottom)
				(hide yes)
			)
		)
		(property "Datasheet" " "
			(at 139.7 248.92 0)
			(effects
				(font
					(size 1.27 1.27)
					(thickness 0.15)
				)
				(justify left bottom)
				(hide yes)
			)
		)
		(property "Description" ""
			(at 154.94 228.6 0)
			(effects
				(font
					(size 1.27 1.27)
				)
			)
		)
		(property "Manufacturer" "Murata"
			(at 134.62 248.92 0)
			(effects
				(font
					(size 1.27 1.27)
					(thickness 0.15)
				)
				(justify left bottom)
				(hide yes)
			)
		)
		(property "MPN" "GRM155R61A475MEAAD"
			(at 137.16 248.92 0)
			(effects
				(font
					(size 1.27 1.27)
					(thickness 0.15)
				)
				(justify left bottom)
				(hide yes)
			)
		)
		(property "Val" "4u7"
			(at 155.575 234.315 90)
			(effects
				(font
					(size 1.27 1.27)
					(thickness 0.15)
				)
				(justify left bottom)
			)
		)
		(property "License" "Apache-2.0"
			(at 132.08 248.92 0)
			(effects
				(font
					(size 1.27 1.27)
					(thickness 0.15)
				)
				(justify left bottom)
				(hide yes)
			)
		)
		(property "Author" "Antmicro"
			(at 129.54 248.92 0)
			(effects
				(font
					(size 1.27 1.27)
					(thickness 0.15)
				)
				(justify left bottom)
				(hide yes)
			)
		)
		(property "Voltage" ""
			(at 127 248.92 0)
			(effects
				(font
					(size 1.27 1.27)
				)
				(justify left bottom)
				(hide yes)
			)
		)
		(property "Dielectric" ""
			(at 124.46 248.92 0)
			(effects
				(font
					(size 1.27 1.27)
				)
				(justify left bottom)
				(hide yes)
			)
		)
		(pin "1"
		)
		(pin "2"
		)
		(instances
			(project "lpddr4-test-board"
				(path ""
					(reference "C68")
					(unit 1)
				)
			)
		)
	)
	(symbol
		(lib_id "antmicroCapacitorsmisc:C_100n_0201")
		(at 99.06 133.35 270)
		(unit 1)
		(exclude_from_sim no)
		(in_bom yes)
		(on_board yes)
		(dnp no)
		(property "Reference" "C49"
			(at 99.695 135.255 90)
			(effects
				(font
					(size 1.27 1.27)
					(thickness 0.15)
				)
				(justify left bottom)
			)
		)
		(property "Value" "C_100n_0201"
			(at 88.9 153.67 0)
			(effects
				(font
					(size 1.27 1.27)
					(thickness 0.15)
				)
				(justify left bottom)
				(hide yes)
			)
		)
		(property "Footprint" "antmicro-footprints:C_0201"
			(at 86.36 153.67 0)
			(effects
				(font
					(size 1.27 1.27)
					(thickness 0.15)
				)
				(justify left bottom)
				(hide yes)
			)
		)
		(property "Datasheet" " "
			(at 83.82 153.67 0)
			(effects
				(font
					(size 1.27 1.27)
					(thickness 0.15)
				)
				(justify left bottom)
				(hide yes)
			)
		)
		(property "Description" ""
			(at 99.06 133.35 0)
			(effects
				(font
					(size 1.27 1.27)
				)
			)
		)
		(property "Manufacturer" "Yaego"
			(at 78.74 153.67 0)
			(effects
				(font
					(size 1.27 1.27)
					(thickness 0.15)
				)
				(justify left bottom)
				(hide yes)
			)
		)
		(property "MPN" "CC0201KRX6S5BB104"
			(at 81.28 153.67 0)
			(effects
				(font
					(size 1.27 1.27)
					(thickness 0.15)
				)
				(justify left bottom)
				(hide yes)
			)
		)
		(property "Val" "100n"
			(at 99.695 139.065 90)
			(effects
				(font
					(size 1.27 1.27)
					(thickness 0.15)
				)
				(justify left bottom)
			)
		)
		(property "License" "Apache-2.0"
			(at 76.2 153.67 0)
			(effects
				(font
					(size 1.27 1.27)
					(thickness 0.15)
				)
				(justify left bottom)
				(hide yes)
			)
		)
		(property "Author" "Antmicro"
			(at 73.66 153.67 0)
			(effects
				(font
					(size 1.27 1.27)
					(thickness 0.15)
				)
				(justify left bottom)
				(hide yes)
			)
		)
		(property "Voltage" ""
			(at 71.12 153.67 0)
			(effects
				(font
					(size 1.27 1.27)
				)
				(justify left bottom)
				(hide yes)
			)
		)
		(property "Dielectric" ""
			(at 68.58 153.67 0)
			(effects
				(font
					(size 1.27 1.27)
				)
				(justify left bottom)
				(hide yes)
			)
		)
		(pin "1"
		)
		(pin "2"
		)
		(instances
			(project "lpddr4-test-board"
				(path ""
					(reference "C49")
					(unit 1)
				)
			)
		)
	)
	(symbol
		(lib_id "antmicroCapacitorsmisc:C_100n_0201")
		(at 106.045 133.35 270)
		(unit 1)
		(exclude_from_sim no)
		(in_bom yes)
		(on_board yes)
		(dnp no)
		(property "Reference" "C53"
			(at 106.68 135.255 90)
			(effects
				(font
					(size 1.27 1.27)
					(thickness 0.15)
				)
				(justify left bottom)
			)
		)
		(property "Value" "C_100n_0201"
			(at 95.885 153.67 0)
			(effects
				(font
					(size 1.27 1.27)
					(thickness 0.15)
				)
				(justify left bottom)
				(hide yes)
			)
		)
		(property "Footprint" "antmicro-footprints:C_0201"
			(at 93.345 153.67 0)
			(effects
				(font
					(size 1.27 1.27)
					(thickness 0.15)
				)
				(justify left bottom)
				(hide yes)
			)
		)
		(property "Datasheet" " "
			(at 90.805 153.67 0)
			(effects
				(font
					(size 1.27 1.27)
					(thickness 0.15)
				)
				(justify left bottom)
				(hide yes)
			)
		)
		(property "Description" ""
			(at 106.045 133.35 0)
			(effects
				(font
					(size 1.27 1.27)
				)
			)
		)
		(property "Manufacturer" "Yaego"
			(at 85.725 153.67 0)
			(effects
				(font
					(size 1.27 1.27)
					(thickness 0.15)
				)
				(justify left bottom)
				(hide yes)
			)
		)
		(property "MPN" "CC0201KRX6S5BB104"
			(at 88.265 153.67 0)
			(effects
				(font
					(size 1.27 1.27)
					(thickness 0.15)
				)
				(justify left bottom)
				(hide yes)
			)
		)
		(property "Val" "100n"
			(at 106.68 139.065 90)
			(effects
				(font
					(size 1.27 1.27)
					(thickness 0.15)
				)
				(justify left bottom)
			)
		)
		(property "License" "Apache-2.0"
			(at 83.185 153.67 0)
			(effects
				(font
					(size 1.27 1.27)
					(thickness 0.15)
				)
				(justify left bottom)
				(hide yes)
			)
		)
		(property "Author" "Antmicro"
			(at 80.645 153.67 0)
			(effects
				(font
					(size 1.27 1.27)
					(thickness 0.15)
				)
				(justify left bottom)
				(hide yes)
			)
		)
		(property "Voltage" ""
			(at 78.105 153.67 0)
			(effects
				(font
					(size 1.27 1.27)
				)
				(justify left bottom)
				(hide yes)
			)
		)
		(property "Dielectric" ""
			(at 75.565 153.67 0)
			(effects
				(font
					(size 1.27 1.27)
				)
				(justify left bottom)
				(hide yes)
			)
		)
		(pin "1"
		)
		(pin "2"
		)
		(instances
			(project "lpddr4-test-board"
				(path ""
					(reference "C53")
					(unit 1)
				)
			)
		)
	)
	(symbol
		(lib_id "antmicroCapacitorsmisc:C_100n_0201")
		(at 113.03 133.35 270)
		(unit 1)
		(exclude_from_sim no)
		(in_bom yes)
		(on_board yes)
		(dnp no)
		(property "Reference" "C57"
			(at 113.665 135.255 90)
			(effects
				(font
					(size 1.27 1.27)
					(thickness 0.15)
				)
				(justify left bottom)
			)
		)
		(property "Value" "C_100n_0201"
			(at 102.87 153.67 0)
			(effects
				(font
					(size 1.27 1.27)
					(thickness 0.15)
				)
				(justify left bottom)
				(hide yes)
			)
		)
		(property "Footprint" "antmicro-footprints:C_0201"
			(at 100.33 153.67 0)
			(effects
				(font
					(size 1.27 1.27)
					(thickness 0.15)
				)
				(justify left bottom)
				(hide yes)
			)
		)
		(property "Datasheet" " "
			(at 97.79 153.67 0)
			(effects
				(font
					(size 1.27 1.27)
					(thickness 0.15)
				)
				(justify left bottom)
				(hide yes)
			)
		)
		(property "Description" ""
			(at 113.03 133.35 0)
			(effects
				(font
					(size 1.27 1.27)
				)
			)
		)
		(property "Manufacturer" "Yaego"
			(at 92.71 153.67 0)
			(effects
				(font
					(size 1.27 1.27)
					(thickness 0.15)
				)
				(justify left bottom)
				(hide yes)
			)
		)
		(property "MPN" "CC0201KRX6S5BB104"
			(at 95.25 153.67 0)
			(effects
				(font
					(size 1.27 1.27)
					(thickness 0.15)
				)
				(justify left bottom)
				(hide yes)
			)
		)
		(property "Val" "100n"
			(at 113.665 139.065 90)
			(effects
				(font
					(size 1.27 1.27)
					(thickness 0.15)
				)
				(justify left bottom)
			)
		)
		(property "License" "Apache-2.0"
			(at 90.17 153.67 0)
			(effects
				(font
					(size 1.27 1.27)
					(thickness 0.15)
				)
				(justify left bottom)
				(hide yes)
			)
		)
		(property "Author" "Antmicro"
			(at 87.63 153.67 0)
			(effects
				(font
					(size 1.27 1.27)
					(thickness 0.15)
				)
				(justify left bottom)
				(hide yes)
			)
		)
		(property "Voltage" ""
			(at 85.09 153.67 0)
			(effects
				(font
					(size 1.27 1.27)
				)
				(justify left bottom)
				(hide yes)
			)
		)
		(property "Dielectric" ""
			(at 82.55 153.67 0)
			(effects
				(font
					(size 1.27 1.27)
				)
				(justify left bottom)
				(hide yes)
			)
		)
		(pin "1"
		)
		(pin "2"
		)
		(instances
			(project "lpddr4-test-board"
				(path ""
					(reference "C57")
					(unit 1)
				)
			)
		)
	)
	(symbol
		(lib_id "antmicroCapacitorsmisc:C_100n_0201")
		(at 120.015 133.35 270)
		(unit 1)
		(exclude_from_sim no)
		(in_bom yes)
		(on_board yes)
		(dnp no)
		(property "Reference" "C60"
			(at 120.65 135.255 90)
			(effects
				(font
					(size 1.27 1.27)
					(thickness 0.15)
				)
				(justify left bottom)
			)
		)
		(property "Value" "C_100n_0201"
			(at 109.855 153.67 0)
			(effects
				(font
					(size 1.27 1.27)
					(thickness 0.15)
				)
				(justify left bottom)
				(hide yes)
			)
		)
		(property "Footprint" "antmicro-footprints:C_0201"
			(at 107.315 153.67 0)
			(effects
				(font
					(size 1.27 1.27)
					(thickness 0.15)
				)
				(justify left bottom)
				(hide yes)
			)
		)
		(property "Datasheet" " "
			(at 104.775 153.67 0)
			(effects
				(font
					(size 1.27 1.27)
					(thickness 0.15)
				)
				(justify left bottom)
				(hide yes)
			)
		)
		(property "Description" ""
			(at 120.015 133.35 0)
			(effects
				(font
					(size 1.27 1.27)
				)
			)
		)
		(property "Manufacturer" "Yaego"
			(at 99.695 153.67 0)
			(effects
				(font
					(size 1.27 1.27)
					(thickness 0.15)
				)
				(justify left bottom)
				(hide yes)
			)
		)
		(property "MPN" "CC0201KRX6S5BB104"
			(at 102.235 153.67 0)
			(effects
				(font
					(size 1.27 1.27)
					(thickness 0.15)
				)
				(justify left bottom)
				(hide yes)
			)
		)
		(property "Val" "100n"
			(at 120.65 139.065 90)
			(effects
				(font
					(size 1.27 1.27)
					(thickness 0.15)
				)
				(justify left bottom)
			)
		)
		(property "License" "Apache-2.0"
			(at 97.155 153.67 0)
			(effects
				(font
					(size 1.27 1.27)
					(thickness 0.15)
				)
				(justify left bottom)
				(hide yes)
			)
		)
		(property "Author" "Antmicro"
			(at 94.615 153.67 0)
			(effects
				(font
					(size 1.27 1.27)
					(thickness 0.15)
				)
				(justify left bottom)
				(hide yes)
			)
		)
		(property "Voltage" ""
			(at 92.075 153.67 0)
			(effects
				(font
					(size 1.27 1.27)
				)
				(justify left bottom)
				(hide yes)
			)
		)
		(property "Dielectric" ""
			(at 89.535 153.67 0)
			(effects
				(font
					(size 1.27 1.27)
				)
				(justify left bottom)
				(hide yes)
			)
		)
		(pin "1"
		)
		(pin "2"
		)
		(instances
			(project "lpddr4-test-board"
				(path ""
					(reference "C60")
					(unit 1)
				)
			)
		)
	)
	(symbol
		(lib_id "antmicroCapacitorsmisc:C_100n_0201")
		(at 127 133.35 270)
		(unit 1)
		(exclude_from_sim no)
		(in_bom yes)
		(on_board yes)
		(dnp no)
		(property "Reference" "C63"
			(at 127.635 135.255 90)
			(effects
				(font
					(size 1.27 1.27)
					(thickness 0.15)
				)
				(justify left bottom)
			)
		)
		(property "Value" "C_100n_0201"
			(at 116.84 153.67 0)
			(effects
				(font
					(size 1.27 1.27)
					(thickness 0.15)
				)
				(justify left bottom)
				(hide yes)
			)
		)
		(property "Footprint" "antmicro-footprints:C_0201"
			(at 114.3 153.67 0)
			(effects
				(font
					(size 1.27 1.27)
					(thickness 0.15)
				)
				(justify left bottom)
				(hide yes)
			)
		)
		(property "Datasheet" " "
			(at 111.76 153.67 0)
			(effects
				(font
					(size 1.27 1.27)
					(thickness 0.15)
				)
				(justify left bottom)
				(hide yes)
			)
		)
		(property "Description" ""
			(at 127 133.35 0)
			(effects
				(font
					(size 1.27 1.27)
				)
			)
		)
		(property "Manufacturer" "Yaego"
			(at 106.68 153.67 0)
			(effects
				(font
					(size 1.27 1.27)
					(thickness 0.15)
				)
				(justify left bottom)
				(hide yes)
			)
		)
		(property "MPN" "CC0201KRX6S5BB104"
			(at 109.22 153.67 0)
			(effects
				(font
					(size 1.27 1.27)
					(thickness 0.15)
				)
				(justify left bottom)
				(hide yes)
			)
		)
		(property "Val" "100n"
			(at 127.635 139.065 90)
			(effects
				(font
					(size 1.27 1.27)
					(thickness 0.15)
				)
				(justify left bottom)
			)
		)
		(property "License" "Apache-2.0"
			(at 104.14 153.67 0)
			(effects
				(font
					(size 1.27 1.27)
					(thickness 0.15)
				)
				(justify left bottom)
				(hide yes)
			)
		)
		(property "Author" "Antmicro"
			(at 101.6 153.67 0)
			(effects
				(font
					(size 1.27 1.27)
					(thickness 0.15)
				)
				(justify left bottom)
				(hide yes)
			)
		)
		(property "Voltage" ""
			(at 99.06 153.67 0)
			(effects
				(font
					(size 1.27 1.27)
				)
				(justify left bottom)
				(hide yes)
			)
		)
		(property "Dielectric" ""
			(at 96.52 153.67 0)
			(effects
				(font
					(size 1.27 1.27)
				)
				(justify left bottom)
				(hide yes)
			)
		)
		(pin "1"
		)
		(pin "2"
		)
		(instances
			(project "lpddr4-test-board"
				(path ""
					(reference "C63")
					(unit 1)
				)
			)
		)
	)
	(symbol
		(lib_id "antmicroCapacitors0402:C_4u7_0402")
		(at 161.925 228.6 270)
		(unit 1)
		(exclude_from_sim no)
		(in_bom yes)
		(on_board yes)
		(dnp no)
		(property "Reference" "C72"
			(at 162.56 230.505 90)
			(effects
				(font
					(size 1.27 1.27)
					(thickness 0.15)
				)
				(justify left bottom)
			)
		)
		(property "Value" "C_4u7_0402"
			(at 151.765 248.92 0)
			(effects
				(font
					(size 1.27 1.27)
					(thickness 0.15)
				)
				(justify left bottom)
				(hide yes)
			)
		)
		(property "Footprint" "antmicro-footprints:C_0402_1005Metric"
			(at 149.225 248.92 0)
			(effects
				(font
					(size 1.27 1.27)
					(thickness 0.15)
				)
				(justify left bottom)
				(hide yes)
			)
		)
		(property "Datasheet" " "
			(at 146.685 248.92 0)
			(effects
				(font
					(size 1.27 1.27)
					(thickness 0.15)
				)
				(justify left bottom)
				(hide yes)
			)
		)
		(property "Description" ""
			(at 161.925 228.6 0)
			(effects
				(font
					(size 1.27 1.27)
				)
			)
		)
		(property "Manufacturer" "Murata"
			(at 141.605 248.92 0)
			(effects
				(font
					(size 1.27 1.27)
					(thickness 0.15)
				)
				(justify left bottom)
				(hide yes)
			)
		)
		(property "MPN" "GRM155R61A475MEAAD"
			(at 144.145 248.92 0)
			(effects
				(font
					(size 1.27 1.27)
					(thickness 0.15)
				)
				(justify left bottom)
				(hide yes)
			)
		)
		(property "Val" "4u7"
			(at 162.56 234.315 90)
			(effects
				(font
					(size 1.27 1.27)
					(thickness 0.15)
				)
				(justify left bottom)
			)
		)
		(property "License" "Apache-2.0"
			(at 139.065 248.92 0)
			(effects
				(font
					(size 1.27 1.27)
					(thickness 0.15)
				)
				(justify left bottom)
				(hide yes)
			)
		)
		(property "Author" "Antmicro"
			(at 136.525 248.92 0)
			(effects
				(font
					(size 1.27 1.27)
					(thickness 0.15)
				)
				(justify left bottom)
				(hide yes)
			)
		)
		(property "Voltage" ""
			(at 133.985 248.92 0)
			(effects
				(font
					(size 1.27 1.27)
				)
				(justify left bottom)
				(hide yes)
			)
		)
		(property "Dielectric" ""
			(at 131.445 248.92 0)
			(effects
				(font
					(size 1.27 1.27)
				)
				(justify left bottom)
				(hide yes)
			)
		)
		(pin "1"
		)
		(pin "2"
		)
		(instances
			(project "lpddr4-test-board"
				(path ""
					(reference "C72")
					(unit 1)
				)
			)
		)
	)
	(symbol
		(lib_id "antmicroCapacitors0603:C_47u_0603")
		(at 92.075 209.55 270)
		(unit 1)
		(exclude_from_sim no)
		(in_bom yes)
		(on_board yes)
		(dnp no)
		(property "Reference" "C93"
			(at 92.71 211.455 90)
			(effects
				(font
					(size 1.27 1.27)
					(thickness 0.15)
				)
				(justify left bottom)
			)
		)
		(property "Value" "C_47u_0603"
			(at 81.915 229.87 0)
			(effects
				(font
					(size 1.27 1.27)
					(thickness 0.15)
				)
				(justify left bottom)
				(hide yes)
			)
		)
		(property "Footprint" "antmicro-footprints:C_0603_1608Metric"
			(at 79.375 229.87 0)
			(effects
				(font
					(size 1.27 1.27)
					(thickness 0.15)
				)
				(justify left bottom)
				(hide yes)
			)
		)
		(property "Datasheet" " "
			(at 76.835 229.87 0)
			(effects
				(font
					(size 1.27 1.27)
					(thickness 0.15)
				)
				(justify left bottom)
				(hide yes)
			)
		)
		(property "Description" ""
			(at 92.075 209.55 0)
			(effects
				(font
					(size 1.27 1.27)
				)
			)
		)
		(property "Manufacturer" "Murata"
			(at 71.755 229.87 0)
			(effects
				(font
					(size 1.27 1.27)
					(thickness 0.15)
				)
				(justify left bottom)
				(hide yes)
			)
		)
		(property "MPN" "GRM188R60J476ME15D"
			(at 74.295 229.87 0)
			(effects
				(font
					(size 1.27 1.27)
					(thickness 0.15)
				)
				(justify left bottom)
				(hide yes)
			)
		)
		(property "Val" "47u"
			(at 92.71 215.265 90)
			(effects
				(font
					(size 1.27 1.27)
					(thickness 0.15)
				)
				(justify left bottom)
			)
		)
		(property "License" "Apache-2.0"
			(at 69.215 229.87 0)
			(effects
				(font
					(size 1.27 1.27)
					(thickness 0.15)
				)
				(justify left bottom)
				(hide yes)
			)
		)
		(property "Author" "Antmicro"
			(at 66.675 229.87 0)
			(effects
				(font
					(size 1.27 1.27)
					(thickness 0.15)
				)
				(justify left bottom)
				(hide yes)
			)
		)
		(property "Voltage" ""
			(at 64.135 229.87 0)
			(effects
				(font
					(size 1.27 1.27)
				)
				(justify left bottom)
				(hide yes)
			)
		)
		(property "Dielectric" ""
			(at 61.595 229.87 0)
			(effects
				(font
					(size 1.27 1.27)
				)
				(justify left bottom)
				(hide yes)
			)
		)
		(pin "1"
		)
		(pin "2"
		)
		(instances
			(project "lpddr4-test-board"
				(path ""
					(reference "C93")
					(unit 1)
				)
			)
		)
	)
	(symbol
		(lib_id "antmicroCapacitors0603:C_47u_0603")
		(at 99.06 209.55 270)
		(unit 1)
		(exclude_from_sim no)
		(in_bom yes)
		(on_board yes)
		(dnp no)
		(property "Reference" "C94"
			(at 99.695 211.455 90)
			(effects
				(font
					(size 1.27 1.27)
					(thickness 0.15)
				)
				(justify left bottom)
			)
		)
		(property "Value" "C_47u_0603"
			(at 88.9 229.87 0)
			(effects
				(font
					(size 1.27 1.27)
					(thickness 0.15)
				)
				(justify left bottom)
				(hide yes)
			)
		)
		(property "Footprint" "antmicro-footprints:C_0603_1608Metric"
			(at 86.36 229.87 0)
			(effects
				(font
					(size 1.27 1.27)
					(thickness 0.15)
				)
				(justify left bottom)
				(hide yes)
			)
		)
		(property "Datasheet" " "
			(at 83.82 229.87 0)
			(effects
				(font
					(size 1.27 1.27)
					(thickness 0.15)
				)
				(justify left bottom)
				(hide yes)
			)
		)
		(property "Description" ""
			(at 99.06 209.55 0)
			(effects
				(font
					(size 1.27 1.27)
				)
			)
		)
		(property "Manufacturer" "Murata"
			(at 78.74 229.87 0)
			(effects
				(font
					(size 1.27 1.27)
					(thickness 0.15)
				)
				(justify left bottom)
				(hide yes)
			)
		)
		(property "MPN" "GRM188R60J476ME15D"
			(at 81.28 229.87 0)
			(effects
				(font
					(size 1.27 1.27)
					(thickness 0.15)
				)
				(justify left bottom)
				(hide yes)
			)
		)
		(property "Val" "47u"
			(at 99.695 215.265 90)
			(effects
				(font
					(size 1.27 1.27)
					(thickness 0.15)
				)
				(justify left bottom)
			)
		)
		(property "License" "Apache-2.0"
			(at 76.2 229.87 0)
			(effects
				(font
					(size 1.27 1.27)
					(thickness 0.15)
				)
				(justify left bottom)
				(hide yes)
			)
		)
		(property "Author" "Antmicro"
			(at 73.66 229.87 0)
			(effects
				(font
					(size 1.27 1.27)
					(thickness 0.15)
				)
				(justify left bottom)
				(hide yes)
			)
		)
		(property "Voltage" ""
			(at 71.12 229.87 0)
			(effects
				(font
					(size 1.27 1.27)
				)
				(justify left bottom)
				(hide yes)
			)
		)
		(property "Dielectric" ""
			(at 68.58 229.87 0)
			(effects
				(font
					(size 1.27 1.27)
				)
				(justify left bottom)
				(hide yes)
			)
		)
		(pin "1"
		)
		(pin "2"
		)
		(instances
			(project "lpddr4-test-board"
				(path ""
					(reference "C94")
					(unit 1)
				)
			)
		)
	)
	(symbol
		(lib_id "antmicroCapacitors0603:C_47u_0603")
		(at 106.045 209.55 270)
		(unit 1)
		(exclude_from_sim no)
		(in_bom yes)
		(on_board yes)
		(dnp no)
		(property "Reference" "C95"
			(at 106.68 211.455 90)
			(effects
				(font
					(size 1.27 1.27)
					(thickness 0.15)
				)
				(justify left bottom)
			)
		)
		(property "Value" "C_47u_0603"
			(at 95.885 229.87 0)
			(effects
				(font
					(size 1.27 1.27)
					(thickness 0.15)
				)
				(justify left bottom)
				(hide yes)
			)
		)
		(property "Footprint" "antmicro-footprints:C_0603_1608Metric"
			(at 93.345 229.87 0)
			(effects
				(font
					(size 1.27 1.27)
					(thickness 0.15)
				)
				(justify left bottom)
				(hide yes)
			)
		)
		(property "Datasheet" " "
			(at 90.805 229.87 0)
			(effects
				(font
					(size 1.27 1.27)
					(thickness 0.15)
				)
				(justify left bottom)
				(hide yes)
			)
		)
		(property "Description" ""
			(at 106.045 209.55 0)
			(effects
				(font
					(size 1.27 1.27)
				)
			)
		)
		(property "Manufacturer" "Murata"
			(at 85.725 229.87 0)
			(effects
				(font
					(size 1.27 1.27)
					(thickness 0.15)
				)
				(justify left bottom)
				(hide yes)
			)
		)
		(property "MPN" "GRM188R60J476ME15D"
			(at 88.265 229.87 0)
			(effects
				(font
					(size 1.27 1.27)
					(thickness 0.15)
				)
				(justify left bottom)
				(hide yes)
			)
		)
		(property "Val" "47u"
			(at 106.68 215.265 90)
			(effects
				(font
					(size 1.27 1.27)
					(thickness 0.15)
				)
				(justify left bottom)
			)
		)
		(property "License" "Apache-2.0"
			(at 83.185 229.87 0)
			(effects
				(font
					(size 1.27 1.27)
					(thickness 0.15)
				)
				(justify left bottom)
				(hide yes)
			)
		)
		(property "Author" "Antmicro"
			(at 80.645 229.87 0)
			(effects
				(font
					(size 1.27 1.27)
					(thickness 0.15)
				)
				(justify left bottom)
				(hide yes)
			)
		)
		(property "Voltage" ""
			(at 78.105 229.87 0)
			(effects
				(font
					(size 1.27 1.27)
				)
				(justify left bottom)
				(hide yes)
			)
		)
		(property "Dielectric" ""
			(at 75.565 229.87 0)
			(effects
				(font
					(size 1.27 1.27)
				)
				(justify left bottom)
				(hide yes)
			)
		)
		(pin "1"
		)
		(pin "2"
		)
		(instances
			(project "lpddr4-test-board"
				(path ""
					(reference "C95")
					(unit 1)
				)
			)
		)
	)
	(symbol
		(lib_id "antmicroCapacitors0603:C_47u_0603")
		(at 113.03 209.55 270)
		(unit 1)
		(exclude_from_sim no)
		(in_bom yes)
		(on_board yes)
		(dnp no)
		(property "Reference" "C96"
			(at 113.665 211.455 90)
			(effects
				(font
					(size 1.27 1.27)
					(thickness 0.15)
				)
				(justify left bottom)
			)
		)
		(property "Value" "C_47u_0603"
			(at 102.87 229.87 0)
			(effects
				(font
					(size 1.27 1.27)
					(thickness 0.15)
				)
				(justify left bottom)
				(hide yes)
			)
		)
		(property "Footprint" "antmicro-footprints:C_0603_1608Metric"
			(at 100.33 229.87 0)
			(effects
				(font
					(size 1.27 1.27)
					(thickness 0.15)
				)
				(justify left bottom)
				(hide yes)
			)
		)
		(property "Datasheet" " "
			(at 97.79 229.87 0)
			(effects
				(font
					(size 1.27 1.27)
					(thickness 0.15)
				)
				(justify left bottom)
				(hide yes)
			)
		)
		(property "Description" ""
			(at 113.03 209.55 0)
			(effects
				(font
					(size 1.27 1.27)
				)
			)
		)
		(property "Manufacturer" "Murata"
			(at 92.71 229.87 0)
			(effects
				(font
					(size 1.27 1.27)
					(thickness 0.15)
				)
				(justify left bottom)
				(hide yes)
			)
		)
		(property "MPN" "GRM188R60J476ME15D"
			(at 95.25 229.87 0)
			(effects
				(font
					(size 1.27 1.27)
					(thickness 0.15)
				)
				(justify left bottom)
				(hide yes)
			)
		)
		(property "Val" "47u"
			(at 113.665 215.265 90)
			(effects
				(font
					(size 1.27 1.27)
					(thickness 0.15)
				)
				(justify left bottom)
			)
		)
		(property "License" "Apache-2.0"
			(at 90.17 229.87 0)
			(effects
				(font
					(size 1.27 1.27)
					(thickness 0.15)
				)
				(justify left bottom)
				(hide yes)
			)
		)
		(property "Author" "Antmicro"
			(at 87.63 229.87 0)
			(effects
				(font
					(size 1.27 1.27)
					(thickness 0.15)
				)
				(justify left bottom)
				(hide yes)
			)
		)
		(property "Voltage" ""
			(at 85.09 229.87 0)
			(effects
				(font
					(size 1.27 1.27)
				)
				(justify left bottom)
				(hide yes)
			)
		)
		(property "Dielectric" ""
			(at 82.55 229.87 0)
			(effects
				(font
					(size 1.27 1.27)
				)
				(justify left bottom)
				(hide yes)
			)
		)
		(pin "1"
		)
		(pin "2"
		)
		(instances
			(project "lpddr4-test-board"
				(path ""
					(reference "C96")
					(unit 1)
				)
			)
		)
	)
	(symbol
		(lib_id "antmicroCapacitors0603:C_47u_0603")
		(at 92.075 152.4 270)
		(unit 1)
		(exclude_from_sim no)
		(in_bom yes)
		(on_board yes)
		(dnp no)
		(property "Reference" "C27"
			(at 92.71 154.305 90)
			(effects
				(font
					(size 1.27 1.27)
					(thickness 0.15)
				)
				(justify left bottom)
			)
		)
		(property "Value" "C_47u_0603"
			(at 81.915 172.72 0)
			(effects
				(font
					(size 1.27 1.27)
					(thickness 0.15)
				)
				(justify left bottom)
				(hide yes)
			)
		)
		(property "Footprint" "antmicro-footprints:C_0603_1608Metric"
			(at 79.375 172.72 0)
			(effects
				(font
					(size 1.27 1.27)
					(thickness 0.15)
				)
				(justify left bottom)
				(hide yes)
			)
		)
		(property "Datasheet" " "
			(at 76.835 172.72 0)
			(effects
				(font
					(size 1.27 1.27)
					(thickness 0.15)
				)
				(justify left bottom)
				(hide yes)
			)
		)
		(property "Description" ""
			(at 92.075 152.4 0)
			(effects
				(font
					(size 1.27 1.27)
				)
			)
		)
		(property "Manufacturer" "Murata"
			(at 71.755 172.72 0)
			(effects
				(font
					(size 1.27 1.27)
					(thickness 0.15)
				)
				(justify left bottom)
				(hide yes)
			)
		)
		(property "MPN" "GRM188R60J476ME15D"
			(at 74.295 172.72 0)
			(effects
				(font
					(size 1.27 1.27)
					(thickness 0.15)
				)
				(justify left bottom)
				(hide yes)
			)
		)
		(property "Val" "47u"
			(at 92.71 158.115 90)
			(effects
				(font
					(size 1.27 1.27)
					(thickness 0.15)
				)
				(justify left bottom)
			)
		)
		(property "License" "Apache-2.0"
			(at 69.215 172.72 0)
			(effects
				(font
					(size 1.27 1.27)
					(thickness 0.15)
				)
				(justify left bottom)
				(hide yes)
			)
		)
		(property "Author" "Antmicro"
			(at 66.675 172.72 0)
			(effects
				(font
					(size 1.27 1.27)
					(thickness 0.15)
				)
				(justify left bottom)
				(hide yes)
			)
		)
		(property "Voltage" ""
			(at 64.135 172.72 0)
			(effects
				(font
					(size 1.27 1.27)
				)
				(justify left bottom)
				(hide yes)
			)
		)
		(property "Dielectric" ""
			(at 61.595 172.72 0)
			(effects
				(font
					(size 1.27 1.27)
				)
				(justify left bottom)
				(hide yes)
			)
		)
		(pin "1"
		)
		(pin "2"
		)
		(instances
			(project "lpddr4-test-board"
				(path ""
					(reference "C27")
					(unit 1)
				)
			)
		)
	)
	(symbol
		(lib_id "antmicroCapacitors0603:C_47u_0603")
		(at 99.06 152.4 270)
		(unit 1)
		(exclude_from_sim no)
		(in_bom yes)
		(on_board yes)
		(dnp no)
		(property "Reference" "C31"
			(at 99.695 154.305 90)
			(effects
				(font
					(size 1.27 1.27)
					(thickness 0.15)
				)
				(justify left bottom)
			)
		)
		(property "Value" "C_47u_0603"
			(at 88.9 172.72 0)
			(effects
				(font
					(size 1.27 1.27)
					(thickness 0.15)
				)
				(justify left bottom)
				(hide yes)
			)
		)
		(property "Footprint" "antmicro-footprints:C_0603_1608Metric"
			(at 86.36 172.72 0)
			(effects
				(font
					(size 1.27 1.27)
					(thickness 0.15)
				)
				(justify left bottom)
				(hide yes)
			)
		)
		(property "Datasheet" " "
			(at 83.82 172.72 0)
			(effects
				(font
					(size 1.27 1.27)
					(thickness 0.15)
				)
				(justify left bottom)
				(hide yes)
			)
		)
		(property "Description" ""
			(at 99.06 152.4 0)
			(effects
				(font
					(size 1.27 1.27)
				)
			)
		)
		(property "Manufacturer" "Murata"
			(at 78.74 172.72 0)
			(effects
				(font
					(size 1.27 1.27)
					(thickness 0.15)
				)
				(justify left bottom)
				(hide yes)
			)
		)
		(property "MPN" "GRM188R60J476ME15D"
			(at 81.28 172.72 0)
			(effects
				(font
					(size 1.27 1.27)
					(thickness 0.15)
				)
				(justify left bottom)
				(hide yes)
			)
		)
		(property "Val" "47u"
			(at 99.695 158.115 90)
			(effects
				(font
					(size 1.27 1.27)
					(thickness 0.15)
				)
				(justify left bottom)
			)
		)
		(property "License" "Apache-2.0"
			(at 76.2 172.72 0)
			(effects
				(font
					(size 1.27 1.27)
					(thickness 0.15)
				)
				(justify left bottom)
				(hide yes)
			)
		)
		(property "Author" "Antmicro"
			(at 73.66 172.72 0)
			(effects
				(font
					(size 1.27 1.27)
					(thickness 0.15)
				)
				(justify left bottom)
				(hide yes)
			)
		)
		(property "Voltage" ""
			(at 71.12 172.72 0)
			(effects
				(font
					(size 1.27 1.27)
				)
				(justify left bottom)
				(hide yes)
			)
		)
		(property "Dielectric" ""
			(at 68.58 172.72 0)
			(effects
				(font
					(size 1.27 1.27)
				)
				(justify left bottom)
				(hide yes)
			)
		)
		(pin "1"
		)
		(pin "2"
		)
		(instances
			(project "lpddr4-test-board"
				(path ""
					(reference "C31")
					(unit 1)
				)
			)
		)
	)
	(symbol
		(lib_id "antmicropower:GND")
		(at 92.075 215.9 0)
		(unit 1)
		(exclude_from_sim no)
		(in_bom yes)
		(on_board yes)
		(dnp no)
		(property "Reference" "#PWR0130"
			(at 100.965 218.44 0)
			(effects
				(font
					(size 1.27 1.27)
					(thickness 0.15)
				)
				(justify left bottom)
				(hide yes)
			)
		)
		(property "Value" "GND"
			(at 90.17 220.345 0)
			(effects
				(font
					(size 1.27 1.27)
					(thickness 0.15)
				)
				(justify left bottom)
			)
		)
		(property "Footprint" ""
			(at 100.965 223.52 0)
			(effects
				(font
					(size 1.27 1.27)
					(thickness 0.15)
				)
				(justify left bottom)
				(hide yes)
			)
		)
		(property "Datasheet" ""
			(at 100.965 228.6 0)
			(effects
				(font
					(size 1.27 1.27)
					(thickness 0.15)
				)
				(justify left bottom)
				(hide yes)
			)
		)
		(property "Description" ""
			(at 92.075 215.9 0)
			(effects
				(font
					(size 1.27 1.27)
				)
			)
		)
		(property "Author" "Antmicro"
			(at 100.965 223.52 0)
			(effects
				(font
					(size 1.27 1.27)
					(thickness 0.15)
				)
				(justify left bottom)
				(hide yes)
			)
		)
		(property "License" "Apache-2.0"
			(at 100.965 226.06 0)
			(effects
				(font
					(size 1.27 1.27)
					(thickness 0.15)
				)
				(justify left bottom)
				(hide yes)
			)
		)
		(pin "1"
		)
		(instances
			(project "lpddr4-test-board"
				(path ""
					(reference "#PWR0130")
					(unit 1)
				)
			)
		)
	)
	(symbol
		(lib_id "antmicropower:GND")
		(at 99.06 215.9 0)
		(unit 1)
		(exclude_from_sim no)
		(in_bom yes)
		(on_board yes)
		(dnp no)
		(property "Reference" "#PWR0131"
			(at 107.95 218.44 0)
			(effects
				(font
					(size 1.27 1.27)
					(thickness 0.15)
				)
				(justify left bottom)
				(hide yes)
			)
		)
		(property "Value" "GND"
			(at 97.155 220.345 0)
			(effects
				(font
					(size 1.27 1.27)
					(thickness 0.15)
				)
				(justify left bottom)
			)
		)
		(property "Footprint" ""
			(at 107.95 223.52 0)
			(effects
				(font
					(size 1.27 1.27)
					(thickness 0.15)
				)
				(justify left bottom)
				(hide yes)
			)
		)
		(property "Datasheet" ""
			(at 107.95 228.6 0)
			(effects
				(font
					(size 1.27 1.27)
					(thickness 0.15)
				)
				(justify left bottom)
				(hide yes)
			)
		)
		(property "Description" ""
			(at 99.06 215.9 0)
			(effects
				(font
					(size 1.27 1.27)
				)
			)
		)
		(property "Author" "Antmicro"
			(at 107.95 223.52 0)
			(effects
				(font
					(size 1.27 1.27)
					(thickness 0.15)
				)
				(justify left bottom)
				(hide yes)
			)
		)
		(property "License" "Apache-2.0"
			(at 107.95 226.06 0)
			(effects
				(font
					(size 1.27 1.27)
					(thickness 0.15)
				)
				(justify left bottom)
				(hide yes)
			)
		)
		(pin "1"
		)
		(instances
			(project "lpddr4-test-board"
				(path ""
					(reference "#PWR0131")
					(unit 1)
				)
			)
		)
	)
	(symbol
		(lib_id "antmicropower:GND")
		(at 106.045 215.9 0)
		(unit 1)
		(exclude_from_sim no)
		(in_bom yes)
		(on_board yes)
		(dnp no)
		(property "Reference" "#PWR0132"
			(at 114.935 218.44 0)
			(effects
				(font
					(size 1.27 1.27)
					(thickness 0.15)
				)
				(justify left bottom)
				(hide yes)
			)
		)
		(property "Value" "GND"
			(at 104.14 220.345 0)
			(effects
				(font
					(size 1.27 1.27)
					(thickness 0.15)
				)
				(justify left bottom)
			)
		)
		(property "Footprint" ""
			(at 114.935 223.52 0)
			(effects
				(font
					(size 1.27 1.27)
					(thickness 0.15)
				)
				(justify left bottom)
				(hide yes)
			)
		)
		(property "Datasheet" ""
			(at 114.935 228.6 0)
			(effects
				(font
					(size 1.27 1.27)
					(thickness 0.15)
				)
				(justify left bottom)
				(hide yes)
			)
		)
		(property "Description" ""
			(at 106.045 215.9 0)
			(effects
				(font
					(size 1.27 1.27)
				)
			)
		)
		(property "Author" "Antmicro"
			(at 114.935 223.52 0)
			(effects
				(font
					(size 1.27 1.27)
					(thickness 0.15)
				)
				(justify left bottom)
				(hide yes)
			)
		)
		(property "License" "Apache-2.0"
			(at 114.935 226.06 0)
			(effects
				(font
					(size 1.27 1.27)
					(thickness 0.15)
				)
				(justify left bottom)
				(hide yes)
			)
		)
		(pin "1"
		)
		(instances
			(project "lpddr4-test-board"
				(path ""
					(reference "#PWR0132")
					(unit 1)
				)
			)
		)
	)
	(symbol
		(lib_id "antmicropower:GND")
		(at 113.03 215.9 0)
		(unit 1)
		(exclude_from_sim no)
		(in_bom yes)
		(on_board yes)
		(dnp no)
		(property "Reference" "#PWR0133"
			(at 121.92 218.44 0)
			(effects
				(font
					(size 1.27 1.27)
					(thickness 0.15)
				)
				(justify left bottom)
				(hide yes)
			)
		)
		(property "Value" "GND"
			(at 111.125 220.345 0)
			(effects
				(font
					(size 1.27 1.27)
					(thickness 0.15)
				)
				(justify left bottom)
			)
		)
		(property "Footprint" ""
			(at 121.92 223.52 0)
			(effects
				(font
					(size 1.27 1.27)
					(thickness 0.15)
				)
				(justify left bottom)
				(hide yes)
			)
		)
		(property "Datasheet" ""
			(at 121.92 228.6 0)
			(effects
				(font
					(size 1.27 1.27)
					(thickness 0.15)
				)
				(justify left bottom)
				(hide yes)
			)
		)
		(property "Description" ""
			(at 113.03 215.9 0)
			(effects
				(font
					(size 1.27 1.27)
				)
			)
		)
		(property "Author" "Antmicro"
			(at 121.92 223.52 0)
			(effects
				(font
					(size 1.27 1.27)
					(thickness 0.15)
				)
				(justify left bottom)
				(hide yes)
			)
		)
		(property "License" "Apache-2.0"
			(at 121.92 226.06 0)
			(effects
				(font
					(size 1.27 1.27)
					(thickness 0.15)
				)
				(justify left bottom)
				(hide yes)
			)
		)
		(pin "1"
		)
		(instances
			(project "lpddr4-test-board"
				(path ""
					(reference "#PWR0133")
					(unit 1)
				)
			)
		)
	)
	(symbol
		(lib_id "antmicroCapacitorsmisc:C_100n_0201")
		(at 92.075 95.25 270)
		(unit 1)
		(exclude_from_sim no)
		(in_bom yes)
		(on_board yes)
		(dnp no)
		(property "Reference" "C25"
			(at 92.71 97.155 90)
			(effects
				(font
					(size 1.27 1.27)
					(thickness 0.15)
				)
				(justify left bottom)
			)
		)
		(property "Value" "C_100n_0201"
			(at 81.915 115.57 0)
			(effects
				(font
					(size 1.27 1.27)
					(thickness 0.15)
				)
				(justify left bottom)
				(hide yes)
			)
		)
		(property "Footprint" "antmicro-footprints:C_0201"
			(at 79.375 115.57 0)
			(effects
				(font
					(size 1.27 1.27)
					(thickness 0.15)
				)
				(justify left bottom)
				(hide yes)
			)
		)
		(property "Datasheet" " "
			(at 76.835 115.57 0)
			(effects
				(font
					(size 1.27 1.27)
					(thickness 0.15)
				)
				(justify left bottom)
				(hide yes)
			)
		)
		(property "Description" ""
			(at 92.075 95.25 0)
			(effects
				(font
					(size 1.27 1.27)
				)
			)
		)
		(property "Manufacturer" "Yaego"
			(at 71.755 115.57 0)
			(effects
				(font
					(size 1.27 1.27)
					(thickness 0.15)
				)
				(justify left bottom)
				(hide yes)
			)
		)
		(property "MPN" "CC0201KRX6S5BB104"
			(at 74.295 115.57 0)
			(effects
				(font
					(size 1.27 1.27)
					(thickness 0.15)
				)
				(justify left bottom)
				(hide yes)
			)
		)
		(property "Val" "100n"
			(at 92.71 100.965 90)
			(effects
				(font
					(size 1.27 1.27)
					(thickness 0.15)
				)
				(justify left bottom)
			)
		)
		(property "License" "Apache-2.0"
			(at 69.215 115.57 0)
			(effects
				(font
					(size 1.27 1.27)
					(thickness 0.15)
				)
				(justify left bottom)
				(hide yes)
			)
		)
		(property "Author" "Antmicro"
			(at 66.675 115.57 0)
			(effects
				(font
					(size 1.27 1.27)
					(thickness 0.15)
				)
				(justify left bottom)
				(hide yes)
			)
		)
		(property "Voltage" ""
			(at 64.135 115.57 0)
			(effects
				(font
					(size 1.27 1.27)
				)
				(justify left bottom)
				(hide yes)
			)
		)
		(property "Dielectric" ""
			(at 61.595 115.57 0)
			(effects
				(font
					(size 1.27 1.27)
				)
				(justify left bottom)
				(hide yes)
			)
		)
		(pin "1"
		)
		(pin "2"
		)
		(instances
			(project "lpddr4-test-board"
				(path ""
					(reference "C25")
					(unit 1)
				)
			)
		)
	)
	(symbol
		(lib_id "antmicropower:GND")
		(at 92.075 101.6 0)
		(unit 1)
		(exclude_from_sim no)
		(in_bom yes)
		(on_board yes)
		(dnp no)
		(property "Reference" "#PWR059"
			(at 100.965 104.14 0)
			(effects
				(font
					(size 1.27 1.27)
					(thickness 0.15)
				)
				(justify left bottom)
				(hide yes)
			)
		)
		(property "Value" "GND"
			(at 90.17 106.045 0)
			(effects
				(font
					(size 1.27 1.27)
					(thickness 0.15)
				)
				(justify left bottom)
			)
		)
		(property "Footprint" ""
			(at 100.965 109.22 0)
			(effects
				(font
					(size 1.27 1.27)
					(thickness 0.15)
				)
				(justify left bottom)
				(hide yes)
			)
		)
		(property "Datasheet" ""
			(at 100.965 114.3 0)
			(effects
				(font
					(size 1.27 1.27)
					(thickness 0.15)
				)
				(justify left bottom)
				(hide yes)
			)
		)
		(property "Description" ""
			(at 92.075 101.6 0)
			(effects
				(font
					(size 1.27 1.27)
				)
			)
		)
		(property "Author" "Antmicro"
			(at 100.965 109.22 0)
			(effects
				(font
					(size 1.27 1.27)
					(thickness 0.15)
				)
				(justify left bottom)
				(hide yes)
			)
		)
		(property "License" "Apache-2.0"
			(at 100.965 111.76 0)
			(effects
				(font
					(size 1.27 1.27)
					(thickness 0.15)
				)
				(justify left bottom)
				(hide yes)
			)
		)
		(pin "1"
		)
		(instances
			(project "lpddr4-test-board"
				(path ""
					(reference "#PWR059")
					(unit 1)
				)
			)
		)
	)
	(symbol
		(lib_id "antmicroCapacitorsmisc:C_100n_0201")
		(at 99.06 95.25 270)
		(unit 1)
		(exclude_from_sim no)
		(in_bom yes)
		(on_board yes)
		(dnp no)
		(property "Reference" "C29"
			(at 99.695 97.155 90)
			(effects
				(font
					(size 1.27 1.27)
					(thickness 0.15)
				)
				(justify left bottom)
			)
		)
		(property "Value" "C_100n_0201"
			(at 88.9 115.57 0)
			(effects
				(font
					(size 1.27 1.27)
					(thickness 0.15)
				)
				(justify left bottom)
				(hide yes)
			)
		)
		(property "Footprint" "antmicro-footprints:C_0201"
			(at 86.36 115.57 0)
			(effects
				(font
					(size 1.27 1.27)
					(thickness 0.15)
				)
				(justify left bottom)
				(hide yes)
			)
		)
		(property "Datasheet" " "
			(at 83.82 115.57 0)
			(effects
				(font
					(size 1.27 1.27)
					(thickness 0.15)
				)
				(justify left bottom)
				(hide yes)
			)
		)
		(property "Description" ""
			(at 99.06 95.25 0)
			(effects
				(font
					(size 1.27 1.27)
				)
			)
		)
		(property "Manufacturer" "Yaego"
			(at 78.74 115.57 0)
			(effects
				(font
					(size 1.27 1.27)
					(thickness 0.15)
				)
				(justify left bottom)
				(hide yes)
			)
		)
		(property "MPN" "CC0201KRX6S5BB104"
			(at 81.28 115.57 0)
			(effects
				(font
					(size 1.27 1.27)
					(thickness 0.15)
				)
				(justify left bottom)
				(hide yes)
			)
		)
		(property "Val" "100n"
			(at 99.695 100.965 90)
			(effects
				(font
					(size 1.27 1.27)
					(thickness 0.15)
				)
				(justify left bottom)
			)
		)
		(property "License" "Apache-2.0"
			(at 76.2 115.57 0)
			(effects
				(font
					(size 1.27 1.27)
					(thickness 0.15)
				)
				(justify left bottom)
				(hide yes)
			)
		)
		(property "Author" "Antmicro"
			(at 73.66 115.57 0)
			(effects
				(font
					(size 1.27 1.27)
					(thickness 0.15)
				)
				(justify left bottom)
				(hide yes)
			)
		)
		(property "Voltage" ""
			(at 71.12 115.57 0)
			(effects
				(font
					(size 1.27 1.27)
				)
				(justify left bottom)
				(hide yes)
			)
		)
		(property "Dielectric" ""
			(at 68.58 115.57 0)
			(effects
				(font
					(size 1.27 1.27)
				)
				(justify left bottom)
				(hide yes)
			)
		)
		(pin "1"
		)
		(pin "2"
		)
		(instances
			(project "lpddr4-test-board"
				(path ""
					(reference "C29")
					(unit 1)
				)
			)
		)
	)
	(symbol
		(lib_id "antmicropower:GND")
		(at 210.82 101.6 0)
		(unit 1)
		(exclude_from_sim no)
		(in_bom yes)
		(on_board yes)
		(dnp no)
		(property "Reference" "#PWR063"
			(at 219.71 104.14 0)
			(effects
				(font
					(size 1.27 1.27)
					(thickness 0.15)
				)
				(justify left bottom)
				(hide yes)
			)
		)
		(property "Value" "GND"
			(at 208.915 106.045 0)
			(effects
				(font
					(size 1.27 1.27)
					(thickness 0.15)
				)
				(justify left bottom)
			)
		)
		(property "Footprint" ""
			(at 219.71 109.22 0)
			(effects
				(font
					(size 1.27 1.27)
					(thickness 0.15)
				)
				(justify left bottom)
				(hide yes)
			)
		)
		(property "Datasheet" ""
			(at 219.71 114.3 0)
			(effects
				(font
					(size 1.27 1.27)
					(thickness 0.15)
				)
				(justify left bottom)
				(hide yes)
			)
		)
		(property "Description" ""
			(at 210.82 101.6 0)
			(effects
				(font
					(size 1.27 1.27)
				)
			)
		)
		(property "Author" "Antmicro"
			(at 219.71 109.22 0)
			(effects
				(font
					(size 1.27 1.27)
					(thickness 0.15)
				)
				(justify left bottom)
				(hide yes)
			)
		)
		(property "License" "Apache-2.0"
			(at 219.71 111.76 0)
			(effects
				(font
					(size 1.27 1.27)
					(thickness 0.15)
				)
				(justify left bottom)
				(hide yes)
			)
		)
		(pin "1"
		)
		(instances
			(project "lpddr4-test-board"
				(path ""
					(reference "#PWR063")
					(unit 1)
				)
			)
		)
	)
	(symbol
		(lib_id "antmicroCapacitorsmisc:C_100n_0201")
		(at 106.045 95.25 270)
		(unit 1)
		(exclude_from_sim no)
		(in_bom yes)
		(on_board yes)
		(dnp no)
		(property "Reference" "C33"
			(at 106.68 97.155 90)
			(effects
				(font
					(size 1.27 1.27)
					(thickness 0.15)
				)
				(justify left bottom)
			)
		)
		(property "Value" "C_100n_0201"
			(at 95.885 115.57 0)
			(effects
				(font
					(size 1.27 1.27)
					(thickness 0.15)
				)
				(justify left bottom)
				(hide yes)
			)
		)
		(property "Footprint" "antmicro-footprints:C_0201"
			(at 93.345 115.57 0)
			(effects
				(font
					(size 1.27 1.27)
					(thickness 0.15)
				)
				(justify left bottom)
				(hide yes)
			)
		)
		(property "Datasheet" " "
			(at 90.805 115.57 0)
			(effects
				(font
					(size 1.27 1.27)
					(thickness 0.15)
				)
				(justify left bottom)
				(hide yes)
			)
		)
		(property "Description" ""
			(at 106.045 95.25 0)
			(effects
				(font
					(size 1.27 1.27)
				)
			)
		)
		(property "Manufacturer" "Yaego"
			(at 85.725 115.57 0)
			(effects
				(font
					(size 1.27 1.27)
					(thickness 0.15)
				)
				(justify left bottom)
				(hide yes)
			)
		)
		(property "MPN" "CC0201KRX6S5BB104"
			(at 88.265 115.57 0)
			(effects
				(font
					(size 1.27 1.27)
					(thickness 0.15)
				)
				(justify left bottom)
				(hide yes)
			)
		)
		(property "Val" "100n"
			(at 106.68 100.965 90)
			(effects
				(font
					(size 1.27 1.27)
					(thickness 0.15)
				)
				(justify left bottom)
			)
		)
		(property "License" "Apache-2.0"
			(at 83.185 115.57 0)
			(effects
				(font
					(size 1.27 1.27)
					(thickness 0.15)
				)
				(justify left bottom)
				(hide yes)
			)
		)
		(property "Author" "Antmicro"
			(at 80.645 115.57 0)
			(effects
				(font
					(size 1.27 1.27)
					(thickness 0.15)
				)
				(justify left bottom)
				(hide yes)
			)
		)
		(property "Voltage" ""
			(at 78.105 115.57 0)
			(effects
				(font
					(size 1.27 1.27)
				)
				(justify left bottom)
				(hide yes)
			)
		)
		(property "Dielectric" ""
			(at 75.565 115.57 0)
			(effects
				(font
					(size 1.27 1.27)
				)
				(justify left bottom)
				(hide yes)
			)
		)
		(pin "1"
		)
		(pin "2"
		)
		(instances
			(project "lpddr4-test-board"
				(path ""
					(reference "C33")
					(unit 1)
				)
			)
		)
	)
	(symbol
		(lib_id "antmicropower:GND")
		(at 203.835 101.6 0)
		(unit 1)
		(exclude_from_sim no)
		(in_bom yes)
		(on_board yes)
		(dnp no)
		(property "Reference" "#PWR067"
			(at 212.725 104.14 0)
			(effects
				(font
					(size 1.27 1.27)
					(thickness 0.15)
				)
				(justify left bottom)
				(hide yes)
			)
		)
		(property "Value" "GND"
			(at 201.93 106.045 0)
			(effects
				(font
					(size 1.27 1.27)
					(thickness 0.15)
				)
				(justify left bottom)
			)
		)
		(property "Footprint" ""
			(at 212.725 109.22 0)
			(effects
				(font
					(size 1.27 1.27)
					(thickness 0.15)
				)
				(justify left bottom)
				(hide yes)
			)
		)
		(property "Datasheet" ""
			(at 212.725 114.3 0)
			(effects
				(font
					(size 1.27 1.27)
					(thickness 0.15)
				)
				(justify left bottom)
				(hide yes)
			)
		)
		(property "Description" ""
			(at 203.835 101.6 0)
			(effects
				(font
					(size 1.27 1.27)
				)
			)
		)
		(property "Author" "Antmicro"
			(at 212.725 109.22 0)
			(effects
				(font
					(size 1.27 1.27)
					(thickness 0.15)
				)
				(justify left bottom)
				(hide yes)
			)
		)
		(property "License" "Apache-2.0"
			(at 212.725 111.76 0)
			(effects
				(font
					(size 1.27 1.27)
					(thickness 0.15)
				)
				(justify left bottom)
				(hide yes)
			)
		)
		(pin "1"
		)
		(instances
			(project "lpddr4-test-board"
				(path ""
					(reference "#PWR067")
					(unit 1)
				)
			)
		)
	)
	(symbol
		(lib_id "antmicroCapacitorsmisc:C_100n_0201")
		(at 113.03 95.25 270)
		(unit 1)
		(exclude_from_sim no)
		(in_bom yes)
		(on_board yes)
		(dnp no)
		(property "Reference" "C37"
			(at 113.665 97.155 90)
			(effects
				(font
					(size 1.27 1.27)
					(thickness 0.15)
				)
				(justify left bottom)
			)
		)
		(property "Value" "C_100n_0201"
			(at 102.87 115.57 0)
			(effects
				(font
					(size 1.27 1.27)
					(thickness 0.15)
				)
				(justify left bottom)
				(hide yes)
			)
		)
		(property "Footprint" "antmicro-footprints:C_0201"
			(at 100.33 115.57 0)
			(effects
				(font
					(size 1.27 1.27)
					(thickness 0.15)
				)
				(justify left bottom)
				(hide yes)
			)
		)
		(property "Datasheet" " "
			(at 97.79 115.57 0)
			(effects
				(font
					(size 1.27 1.27)
					(thickness 0.15)
				)
				(justify left bottom)
				(hide yes)
			)
		)
		(property "Description" ""
			(at 113.03 95.25 0)
			(effects
				(font
					(size 1.27 1.27)
				)
			)
		)
		(property "Manufacturer" "Yaego"
			(at 92.71 115.57 0)
			(effects
				(font
					(size 1.27 1.27)
					(thickness 0.15)
				)
				(justify left bottom)
				(hide yes)
			)
		)
		(property "MPN" "CC0201KRX6S5BB104"
			(at 95.25 115.57 0)
			(effects
				(font
					(size 1.27 1.27)
					(thickness 0.15)
				)
				(justify left bottom)
				(hide yes)
			)
		)
		(property "Val" "100n"
			(at 113.665 100.965 90)
			(effects
				(font
					(size 1.27 1.27)
					(thickness 0.15)
				)
				(justify left bottom)
			)
		)
		(property "License" "Apache-2.0"
			(at 90.17 115.57 0)
			(effects
				(font
					(size 1.27 1.27)
					(thickness 0.15)
				)
				(justify left bottom)
				(hide yes)
			)
		)
		(property "Author" "Antmicro"
			(at 87.63 115.57 0)
			(effects
				(font
					(size 1.27 1.27)
					(thickness 0.15)
				)
				(justify left bottom)
				(hide yes)
			)
		)
		(property "Voltage" ""
			(at 85.09 115.57 0)
			(effects
				(font
					(size 1.27 1.27)
				)
				(justify left bottom)
				(hide yes)
			)
		)
		(property "Dielectric" ""
			(at 82.55 115.57 0)
			(effects
				(font
					(size 1.27 1.27)
				)
				(justify left bottom)
				(hide yes)
			)
		)
		(pin "1"
		)
		(pin "2"
		)
		(instances
			(project "lpddr4-test-board"
				(path ""
					(reference "C37")
					(unit 1)
				)
			)
		)
	)
	(symbol
		(lib_id "antmicropower:GND")
		(at 196.85 101.6 0)
		(unit 1)
		(exclude_from_sim no)
		(in_bom yes)
		(on_board yes)
		(dnp no)
		(property "Reference" "#PWR071"
			(at 205.74 104.14 0)
			(effects
				(font
					(size 1.27 1.27)
					(thickness 0.15)
				)
				(justify left bottom)
				(hide yes)
			)
		)
		(property "Value" "GND"
			(at 194.945 106.045 0)
			(effects
				(font
					(size 1.27 1.27)
					(thickness 0.15)
				)
				(justify left bottom)
			)
		)
		(property "Footprint" ""
			(at 205.74 109.22 0)
			(effects
				(font
					(size 1.27 1.27)
					(thickness 0.15)
				)
				(justify left bottom)
				(hide yes)
			)
		)
		(property "Datasheet" ""
			(at 205.74 114.3 0)
			(effects
				(font
					(size 1.27 1.27)
					(thickness 0.15)
				)
				(justify left bottom)
				(hide yes)
			)
		)
		(property "Description" ""
			(at 196.85 101.6 0)
			(effects
				(font
					(size 1.27 1.27)
				)
			)
		)
		(property "Author" "Antmicro"
			(at 205.74 109.22 0)
			(effects
				(font
					(size 1.27 1.27)
					(thickness 0.15)
				)
				(justify left bottom)
				(hide yes)
			)
		)
		(property "License" "Apache-2.0"
			(at 205.74 111.76 0)
			(effects
				(font
					(size 1.27 1.27)
					(thickness 0.15)
				)
				(justify left bottom)
				(hide yes)
			)
		)
		(pin "1"
		)
		(instances
			(project "lpddr4-test-board"
				(path ""
					(reference "#PWR071")
					(unit 1)
				)
			)
		)
	)
	(symbol
		(lib_id "antmicroCapacitorsmisc:C_100n_0201")
		(at 120.015 95.25 270)
		(unit 1)
		(exclude_from_sim no)
		(in_bom yes)
		(on_board yes)
		(dnp no)
		(property "Reference" "C41"
			(at 120.65 97.155 90)
			(effects
				(font
					(size 1.27 1.27)
					(thickness 0.15)
				)
				(justify left bottom)
			)
		)
		(property "Value" "C_100n_0201"
			(at 109.855 115.57 0)
			(effects
				(font
					(size 1.27 1.27)
					(thickness 0.15)
				)
				(justify left bottom)
				(hide yes)
			)
		)
		(property "Footprint" "antmicro-footprints:C_0201"
			(at 107.315 115.57 0)
			(effects
				(font
					(size 1.27 1.27)
					(thickness 0.15)
				)
				(justify left bottom)
				(hide yes)
			)
		)
		(property "Datasheet" " "
			(at 104.775 115.57 0)
			(effects
				(font
					(size 1.27 1.27)
					(thickness 0.15)
				)
				(justify left bottom)
				(hide yes)
			)
		)
		(property "Description" ""
			(at 120.015 95.25 0)
			(effects
				(font
					(size 1.27 1.27)
				)
			)
		)
		(property "Manufacturer" "Yaego"
			(at 99.695 115.57 0)
			(effects
				(font
					(size 1.27 1.27)
					(thickness 0.15)
				)
				(justify left bottom)
				(hide yes)
			)
		)
		(property "MPN" "CC0201KRX6S5BB104"
			(at 102.235 115.57 0)
			(effects
				(font
					(size 1.27 1.27)
					(thickness 0.15)
				)
				(justify left bottom)
				(hide yes)
			)
		)
		(property "Val" "100n"
			(at 120.65 100.965 90)
			(effects
				(font
					(size 1.27 1.27)
					(thickness 0.15)
				)
				(justify left bottom)
			)
		)
		(property "License" "Apache-2.0"
			(at 97.155 115.57 0)
			(effects
				(font
					(size 1.27 1.27)
					(thickness 0.15)
				)
				(justify left bottom)
				(hide yes)
			)
		)
		(property "Author" "Antmicro"
			(at 94.615 115.57 0)
			(effects
				(font
					(size 1.27 1.27)
					(thickness 0.15)
				)
				(justify left bottom)
				(hide yes)
			)
		)
		(property "Voltage" ""
			(at 92.075 115.57 0)
			(effects
				(font
					(size 1.27 1.27)
				)
				(justify left bottom)
				(hide yes)
			)
		)
		(property "Dielectric" ""
			(at 89.535 115.57 0)
			(effects
				(font
					(size 1.27 1.27)
				)
				(justify left bottom)
				(hide yes)
			)
		)
		(pin "1"
		)
		(pin "2"
		)
		(instances
			(project "lpddr4-test-board"
				(path ""
					(reference "C41")
					(unit 1)
				)
			)
		)
	)
	(symbol
		(lib_id "antmicropower:GND")
		(at 189.865 101.6 0)
		(unit 1)
		(exclude_from_sim no)
		(in_bom yes)
		(on_board yes)
		(dnp no)
		(property "Reference" "#PWR075"
			(at 198.755 104.14 0)
			(effects
				(font
					(size 1.27 1.27)
					(thickness 0.15)
				)
				(justify left bottom)
				(hide yes)
			)
		)
		(property "Value" "GND"
			(at 187.96 106.045 0)
			(effects
				(font
					(size 1.27 1.27)
					(thickness 0.15)
				)
				(justify left bottom)
			)
		)
		(property "Footprint" ""
			(at 198.755 109.22 0)
			(effects
				(font
					(size 1.27 1.27)
					(thickness 0.15)
				)
				(justify left bottom)
				(hide yes)
			)
		)
		(property "Datasheet" ""
			(at 198.755 114.3 0)
			(effects
				(font
					(size 1.27 1.27)
					(thickness 0.15)
				)
				(justify left bottom)
				(hide yes)
			)
		)
		(property "Description" ""
			(at 189.865 101.6 0)
			(effects
				(font
					(size 1.27 1.27)
				)
			)
		)
		(property "Author" "Antmicro"
			(at 198.755 109.22 0)
			(effects
				(font
					(size 1.27 1.27)
					(thickness 0.15)
				)
				(justify left bottom)
				(hide yes)
			)
		)
		(property "License" "Apache-2.0"
			(at 198.755 111.76 0)
			(effects
				(font
					(size 1.27 1.27)
					(thickness 0.15)
				)
				(justify left bottom)
				(hide yes)
			)
		)
		(pin "1"
		)
		(instances
			(project "lpddr4-test-board"
				(path ""
					(reference "#PWR075")
					(unit 1)
				)
			)
		)
	)
	(symbol
		(lib_id "antmicroCapacitorsmisc:C_100n_0201")
		(at 133.985 133.35 270)
		(unit 1)
		(exclude_from_sim no)
		(in_bom yes)
		(on_board yes)
		(dnp no)
		(property "Reference" "C67"
			(at 134.62 135.255 90)
			(effects
				(font
					(size 1.27 1.27)
					(thickness 0.15)
				)
				(justify left bottom)
			)
		)
		(property "Value" "C_100n_0201"
			(at 123.825 153.67 0)
			(effects
				(font
					(size 1.27 1.27)
					(thickness 0.15)
				)
				(justify left bottom)
				(hide yes)
			)
		)
		(property "Footprint" "antmicro-footprints:C_0201"
			(at 121.285 153.67 0)
			(effects
				(font
					(size 1.27 1.27)
					(thickness 0.15)
				)
				(justify left bottom)
				(hide yes)
			)
		)
		(property "Datasheet" " "
			(at 118.745 153.67 0)
			(effects
				(font
					(size 1.27 1.27)
					(thickness 0.15)
				)
				(justify left bottom)
				(hide yes)
			)
		)
		(property "Description" ""
			(at 133.985 133.35 0)
			(effects
				(font
					(size 1.27 1.27)
				)
			)
		)
		(property "Manufacturer" "Yaego"
			(at 113.665 153.67 0)
			(effects
				(font
					(size 1.27 1.27)
					(thickness 0.15)
				)
				(justify left bottom)
				(hide yes)
			)
		)
		(property "MPN" "CC0201KRX6S5BB104"
			(at 116.205 153.67 0)
			(effects
				(font
					(size 1.27 1.27)
					(thickness 0.15)
				)
				(justify left bottom)
				(hide yes)
			)
		)
		(property "Val" "100n"
			(at 134.62 139.065 90)
			(effects
				(font
					(size 1.27 1.27)
					(thickness 0.15)
				)
				(justify left bottom)
			)
		)
		(property "License" "Apache-2.0"
			(at 111.125 153.67 0)
			(effects
				(font
					(size 1.27 1.27)
					(thickness 0.15)
				)
				(justify left bottom)
				(hide yes)
			)
		)
		(property "Author" "Antmicro"
			(at 108.585 153.67 0)
			(effects
				(font
					(size 1.27 1.27)
					(thickness 0.15)
				)
				(justify left bottom)
				(hide yes)
			)
		)
		(property "Voltage" ""
			(at 106.045 153.67 0)
			(effects
				(font
					(size 1.27 1.27)
				)
				(justify left bottom)
				(hide yes)
			)
		)
		(property "Dielectric" ""
			(at 103.505 153.67 0)
			(effects
				(font
					(size 1.27 1.27)
				)
				(justify left bottom)
				(hide yes)
			)
		)
		(pin "1"
		)
		(pin "2"
		)
		(instances
			(project "lpddr4-test-board"
				(path ""
					(reference "C67")
					(unit 1)
				)
			)
		)
	)
	(symbol
		(lib_id "antmicroCapacitors0402:C_4u7_0402")
		(at 168.91 228.6 270)
		(unit 1)
		(exclude_from_sim no)
		(in_bom yes)
		(on_board yes)
		(dnp no)
		(property "Reference" "C77"
			(at 169.545 230.505 90)
			(effects
				(font
					(size 1.27 1.27)
					(thickness 0.15)
				)
				(justify left bottom)
			)
		)
		(property "Value" "C_4u7_0402"
			(at 158.75 248.92 0)
			(effects
				(font
					(size 1.27 1.27)
					(thickness 0.15)
				)
				(justify left bottom)
				(hide yes)
			)
		)
		(property "Footprint" "antmicro-footprints:C_0402_1005Metric"
			(at 156.21 248.92 0)
			(effects
				(font
					(size 1.27 1.27)
					(thickness 0.15)
				)
				(justify left bottom)
				(hide yes)
			)
		)
		(property "Datasheet" " "
			(at 153.67 248.92 0)
			(effects
				(font
					(size 1.27 1.27)
					(thickness 0.15)
				)
				(justify left bottom)
				(hide yes)
			)
		)
		(property "Description" ""
			(at 168.91 228.6 0)
			(effects
				(font
					(size 1.27 1.27)
				)
			)
		)
		(property "Manufacturer" "Murata"
			(at 148.59 248.92 0)
			(effects
				(font
					(size 1.27 1.27)
					(thickness 0.15)
				)
				(justify left bottom)
				(hide yes)
			)
		)
		(property "MPN" "GRM155R61A475MEAAD"
			(at 151.13 248.92 0)
			(effects
				(font
					(size 1.27 1.27)
					(thickness 0.15)
				)
				(justify left bottom)
				(hide yes)
			)
		)
		(property "Val" "4u7"
			(at 169.545 234.315 90)
			(effects
				(font
					(size 1.27 1.27)
					(thickness 0.15)
				)
				(justify left bottom)
			)
		)
		(property "License" "Apache-2.0"
			(at 146.05 248.92 0)
			(effects
				(font
					(size 1.27 1.27)
					(thickness 0.15)
				)
				(justify left bottom)
				(hide yes)
			)
		)
		(property "Author" "Antmicro"
			(at 143.51 248.92 0)
			(effects
				(font
					(size 1.27 1.27)
					(thickness 0.15)
				)
				(justify left bottom)
				(hide yes)
			)
		)
		(property "Voltage" ""
			(at 140.97 248.92 0)
			(effects
				(font
					(size 1.27 1.27)
				)
				(justify left bottom)
				(hide yes)
			)
		)
		(property "Dielectric" ""
			(at 138.43 248.92 0)
			(effects
				(font
					(size 1.27 1.27)
				)
				(justify left bottom)
				(hide yes)
			)
		)
		(pin "1"
		)
		(pin "2"
		)
		(instances
			(project "lpddr4-test-board"
				(path ""
					(reference "C77")
					(unit 1)
				)
			)
		)
	)
	(symbol
		(lib_id "antmicroCapacitors0402:C_4u7_0402")
		(at 175.895 228.6 270)
		(unit 1)
		(exclude_from_sim no)
		(in_bom yes)
		(on_board yes)
		(dnp no)
		(property "Reference" "C79"
			(at 176.53 230.505 90)
			(effects
				(font
					(size 1.27 1.27)
					(thickness 0.15)
				)
				(justify left bottom)
			)
		)
		(property "Value" "C_4u7_0402"
			(at 165.735 248.92 0)
			(effects
				(font
					(size 1.27 1.27)
					(thickness 0.15)
				)
				(justify left bottom)
				(hide yes)
			)
		)
		(property "Footprint" "antmicro-footprints:C_0402_1005Metric"
			(at 163.195 248.92 0)
			(effects
				(font
					(size 1.27 1.27)
					(thickness 0.15)
				)
				(justify left bottom)
				(hide yes)
			)
		)
		(property "Datasheet" " "
			(at 160.655 248.92 0)
			(effects
				(font
					(size 1.27 1.27)
					(thickness 0.15)
				)
				(justify left bottom)
				(hide yes)
			)
		)
		(property "Description" ""
			(at 175.895 228.6 0)
			(effects
				(font
					(size 1.27 1.27)
				)
			)
		)
		(property "Manufacturer" "Murata"
			(at 155.575 248.92 0)
			(effects
				(font
					(size 1.27 1.27)
					(thickness 0.15)
				)
				(justify left bottom)
				(hide yes)
			)
		)
		(property "MPN" "GRM155R61A475MEAAD"
			(at 158.115 248.92 0)
			(effects
				(font
					(size 1.27 1.27)
					(thickness 0.15)
				)
				(justify left bottom)
				(hide yes)
			)
		)
		(property "Val" "4u7"
			(at 176.53 234.315 90)
			(effects
				(font
					(size 1.27 1.27)
					(thickness 0.15)
				)
				(justify left bottom)
			)
		)
		(property "License" "Apache-2.0"
			(at 153.035 248.92 0)
			(effects
				(font
					(size 1.27 1.27)
					(thickness 0.15)
				)
				(justify left bottom)
				(hide yes)
			)
		)
		(property "Author" "Antmicro"
			(at 150.495 248.92 0)
			(effects
				(font
					(size 1.27 1.27)
					(thickness 0.15)
				)
				(justify left bottom)
				(hide yes)
			)
		)
		(property "Voltage" ""
			(at 147.955 248.92 0)
			(effects
				(font
					(size 1.27 1.27)
				)
				(justify left bottom)
				(hide yes)
			)
		)
		(property "Dielectric" ""
			(at 145.415 248.92 0)
			(effects
				(font
					(size 1.27 1.27)
				)
				(justify left bottom)
				(hide yes)
			)
		)
		(pin "1"
		)
		(pin "2"
		)
		(instances
			(project "lpddr4-test-board"
				(path ""
					(reference "C79")
					(unit 1)
				)
			)
		)
	)
	(symbol
		(lib_id "antmicroCapacitorsmisc:C_100n_0201")
		(at 127 95.25 270)
		(unit 1)
		(exclude_from_sim no)
		(in_bom yes)
		(on_board yes)
		(dnp no)
		(property "Reference" "C44"
			(at 127.635 97.155 90)
			(effects
				(font
					(size 1.27 1.27)
					(thickness 0.15)
				)
				(justify left bottom)
			)
		)
		(property "Value" "C_100n_0201"
			(at 116.84 115.57 0)
			(effects
				(font
					(size 1.27 1.27)
					(thickness 0.15)
				)
				(justify left bottom)
				(hide yes)
			)
		)
		(property "Footprint" "antmicro-footprints:C_0201"
			(at 114.3 115.57 0)
			(effects
				(font
					(size 1.27 1.27)
					(thickness 0.15)
				)
				(justify left bottom)
				(hide yes)
			)
		)
		(property "Datasheet" " "
			(at 111.76 115.57 0)
			(effects
				(font
					(size 1.27 1.27)
					(thickness 0.15)
				)
				(justify left bottom)
				(hide yes)
			)
		)
		(property "Description" ""
			(at 127 95.25 0)
			(effects
				(font
					(size 1.27 1.27)
				)
			)
		)
		(property "Manufacturer" "Yaego"
			(at 106.68 115.57 0)
			(effects
				(font
					(size 1.27 1.27)
					(thickness 0.15)
				)
				(justify left bottom)
				(hide yes)
			)
		)
		(property "MPN" "CC0201KRX6S5BB104"
			(at 109.22 115.57 0)
			(effects
				(font
					(size 1.27 1.27)
					(thickness 0.15)
				)
				(justify left bottom)
				(hide yes)
			)
		)
		(property "Val" "100n"
			(at 127.635 100.965 90)
			(effects
				(font
					(size 1.27 1.27)
					(thickness 0.15)
				)
				(justify left bottom)
			)
		)
		(property "License" "Apache-2.0"
			(at 104.14 115.57 0)
			(effects
				(font
					(size 1.27 1.27)
					(thickness 0.15)
				)
				(justify left bottom)
				(hide yes)
			)
		)
		(property "Author" "Antmicro"
			(at 101.6 115.57 0)
			(effects
				(font
					(size 1.27 1.27)
					(thickness 0.15)
				)
				(justify left bottom)
				(hide yes)
			)
		)
		(property "Voltage" ""
			(at 99.06 115.57 0)
			(effects
				(font
					(size 1.27 1.27)
				)
				(justify left bottom)
				(hide yes)
			)
		)
		(property "Dielectric" ""
			(at 96.52 115.57 0)
			(effects
				(font
					(size 1.27 1.27)
				)
				(justify left bottom)
				(hide yes)
			)
		)
		(pin "1"
		)
		(pin "2"
		)
		(instances
			(project "lpddr4-test-board"
				(path ""
					(reference "C44")
					(unit 1)
				)
			)
		)
	)
	(symbol
		(lib_id "antmicropower:GND")
		(at 182.88 101.6 0)
		(unit 1)
		(exclude_from_sim no)
		(in_bom yes)
		(on_board yes)
		(dnp no)
		(property "Reference" "#PWR078"
			(at 191.77 104.14 0)
			(effects
				(font
					(size 1.27 1.27)
					(thickness 0.15)
				)
				(justify left bottom)
				(hide yes)
			)
		)
		(property "Value" "GND"
			(at 180.975 106.045 0)
			(effects
				(font
					(size 1.27 1.27)
					(thickness 0.15)
				)
				(justify left bottom)
			)
		)
		(property "Footprint" ""
			(at 191.77 109.22 0)
			(effects
				(font
					(size 1.27 1.27)
					(thickness 0.15)
				)
				(justify left bottom)
				(hide yes)
			)
		)
		(property "Datasheet" ""
			(at 191.77 114.3 0)
			(effects
				(font
					(size 1.27 1.27)
					(thickness 0.15)
				)
				(justify left bottom)
				(hide yes)
			)
		)
		(property "Description" ""
			(at 182.88 101.6 0)
			(effects
				(font
					(size 1.27 1.27)
				)
			)
		)
		(property "Author" "Antmicro"
			(at 191.77 109.22 0)
			(effects
				(font
					(size 1.27 1.27)
					(thickness 0.15)
				)
				(justify left bottom)
				(hide yes)
			)
		)
		(property "License" "Apache-2.0"
			(at 191.77 111.76 0)
			(effects
				(font
					(size 1.27 1.27)
					(thickness 0.15)
				)
				(justify left bottom)
				(hide yes)
			)
		)
		(pin "1"
		)
		(instances
			(project "lpddr4-test-board"
				(path ""
					(reference "#PWR078")
					(unit 1)
				)
			)
		)
	)
	(symbol
		(lib_id "antmicroCapacitorsmisc:C_100n_0201")
		(at 133.985 95.25 270)
		(unit 1)
		(exclude_from_sim no)
		(in_bom yes)
		(on_board yes)
		(dnp no)
		(property "Reference" "C48"
			(at 134.62 97.155 90)
			(effects
				(font
					(size 1.27 1.27)
					(thickness 0.15)
				)
				(justify left bottom)
			)
		)
		(property "Value" "C_100n_0201"
			(at 123.825 115.57 0)
			(effects
				(font
					(size 1.27 1.27)
					(thickness 0.15)
				)
				(justify left bottom)
				(hide yes)
			)
		)
		(property "Footprint" "antmicro-footprints:C_0201"
			(at 121.285 115.57 0)
			(effects
				(font
					(size 1.27 1.27)
					(thickness 0.15)
				)
				(justify left bottom)
				(hide yes)
			)
		)
		(property "Datasheet" " "
			(at 118.745 115.57 0)
			(effects
				(font
					(size 1.27 1.27)
					(thickness 0.15)
				)
				(justify left bottom)
				(hide yes)
			)
		)
		(property "Description" ""
			(at 133.985 95.25 0)
			(effects
				(font
					(size 1.27 1.27)
				)
			)
		)
		(property "Manufacturer" "Yaego"
			(at 113.665 115.57 0)
			(effects
				(font
					(size 1.27 1.27)
					(thickness 0.15)
				)
				(justify left bottom)
				(hide yes)
			)
		)
		(property "MPN" "CC0201KRX6S5BB104"
			(at 116.205 115.57 0)
			(effects
				(font
					(size 1.27 1.27)
					(thickness 0.15)
				)
				(justify left bottom)
				(hide yes)
			)
		)
		(property "Val" "100n"
			(at 134.62 100.965 90)
			(effects
				(font
					(size 1.27 1.27)
					(thickness 0.15)
				)
				(justify left bottom)
			)
		)
		(property "License" "Apache-2.0"
			(at 111.125 115.57 0)
			(effects
				(font
					(size 1.27 1.27)
					(thickness 0.15)
				)
				(justify left bottom)
				(hide yes)
			)
		)
		(property "Author" "Antmicro"
			(at 108.585 115.57 0)
			(effects
				(font
					(size 1.27 1.27)
					(thickness 0.15)
				)
				(justify left bottom)
				(hide yes)
			)
		)
		(property "Voltage" ""
			(at 106.045 115.57 0)
			(effects
				(font
					(size 1.27 1.27)
				)
				(justify left bottom)
				(hide yes)
			)
		)
		(property "Dielectric" ""
			(at 103.505 115.57 0)
			(effects
				(font
					(size 1.27 1.27)
				)
				(justify left bottom)
				(hide yes)
			)
		)
		(pin "1"
		)
		(pin "2"
		)
		(instances
			(project "lpddr4-test-board"
				(path ""
					(reference "C48")
					(unit 1)
				)
			)
		)
	)
	(symbol
		(lib_id "antmicropower:GND")
		(at 175.895 101.6 0)
		(unit 1)
		(exclude_from_sim no)
		(in_bom yes)
		(on_board yes)
		(dnp no)
		(property "Reference" "#PWR082"
			(at 184.785 104.14 0)
			(effects
				(font
					(size 1.27 1.27)
					(thickness 0.15)
				)
				(justify left bottom)
				(hide yes)
			)
		)
		(property "Value" "GND"
			(at 173.99 106.045 0)
			(effects
				(font
					(size 1.27 1.27)
					(thickness 0.15)
				)
				(justify left bottom)
			)
		)
		(property "Footprint" ""
			(at 184.785 109.22 0)
			(effects
				(font
					(size 1.27 1.27)
					(thickness 0.15)
				)
				(justify left bottom)
				(hide yes)
			)
		)
		(property "Datasheet" ""
			(at 184.785 114.3 0)
			(effects
				(font
					(size 1.27 1.27)
					(thickness 0.15)
				)
				(justify left bottom)
				(hide yes)
			)
		)
		(property "Description" ""
			(at 175.895 101.6 0)
			(effects
				(font
					(size 1.27 1.27)
				)
			)
		)
		(property "Author" "Antmicro"
			(at 184.785 109.22 0)
			(effects
				(font
					(size 1.27 1.27)
					(thickness 0.15)
				)
				(justify left bottom)
				(hide yes)
			)
		)
		(property "License" "Apache-2.0"
			(at 184.785 111.76 0)
			(effects
				(font
					(size 1.27 1.27)
					(thickness 0.15)
				)
				(justify left bottom)
				(hide yes)
			)
		)
		(pin "1"
		)
		(instances
			(project "lpddr4-test-board"
				(path ""
					(reference "#PWR082")
					(unit 1)
				)
			)
		)
	)
	(symbol
		(lib_id "antmicroCapacitorsmisc:C_100n_0201")
		(at 140.97 95.25 270)
		(unit 1)
		(exclude_from_sim no)
		(in_bom yes)
		(on_board yes)
		(dnp no)
		(property "Reference" "C52"
			(at 141.605 97.155 90)
			(effects
				(font
					(size 1.27 1.27)
					(thickness 0.15)
				)
				(justify left bottom)
			)
		)
		(property "Value" "C_100n_0201"
			(at 130.81 115.57 0)
			(effects
				(font
					(size 1.27 1.27)
					(thickness 0.15)
				)
				(justify left bottom)
				(hide yes)
			)
		)
		(property "Footprint" "antmicro-footprints:C_0201"
			(at 128.27 115.57 0)
			(effects
				(font
					(size 1.27 1.27)
					(thickness 0.15)
				)
				(justify left bottom)
				(hide yes)
			)
		)
		(property "Datasheet" " "
			(at 125.73 115.57 0)
			(effects
				(font
					(size 1.27 1.27)
					(thickness 0.15)
				)
				(justify left bottom)
				(hide yes)
			)
		)
		(property "Description" ""
			(at 140.97 95.25 0)
			(effects
				(font
					(size 1.27 1.27)
				)
			)
		)
		(property "Manufacturer" "Yaego"
			(at 120.65 115.57 0)
			(effects
				(font
					(size 1.27 1.27)
					(thickness 0.15)
				)
				(justify left bottom)
				(hide yes)
			)
		)
		(property "MPN" "CC0201KRX6S5BB104"
			(at 123.19 115.57 0)
			(effects
				(font
					(size 1.27 1.27)
					(thickness 0.15)
				)
				(justify left bottom)
				(hide yes)
			)
		)
		(property "Val" "100n"
			(at 141.605 100.965 90)
			(effects
				(font
					(size 1.27 1.27)
					(thickness 0.15)
				)
				(justify left bottom)
			)
		)
		(property "License" "Apache-2.0"
			(at 118.11 115.57 0)
			(effects
				(font
					(size 1.27 1.27)
					(thickness 0.15)
				)
				(justify left bottom)
				(hide yes)
			)
		)
		(property "Author" "Antmicro"
			(at 115.57 115.57 0)
			(effects
				(font
					(size 1.27 1.27)
					(thickness 0.15)
				)
				(justify left bottom)
				(hide yes)
			)
		)
		(property "Voltage" ""
			(at 113.03 115.57 0)
			(effects
				(font
					(size 1.27 1.27)
				)
				(justify left bottom)
				(hide yes)
			)
		)
		(property "Dielectric" ""
			(at 110.49 115.57 0)
			(effects
				(font
					(size 1.27 1.27)
				)
				(justify left bottom)
				(hide yes)
			)
		)
		(pin "1"
		)
		(pin "2"
		)
		(instances
			(project "lpddr4-test-board"
				(path ""
					(reference "C52")
					(unit 1)
				)
			)
		)
	)
	(symbol
		(lib_id "antmicropower:GND")
		(at 168.91 101.6 0)
		(unit 1)
		(exclude_from_sim no)
		(in_bom yes)
		(on_board yes)
		(dnp no)
		(property "Reference" "#PWR086"
			(at 177.8 104.14 0)
			(effects
				(font
					(size 1.27 1.27)
					(thickness 0.15)
				)
				(justify left bottom)
				(hide yes)
			)
		)
		(property "Value" "GND"
			(at 167.005 106.045 0)
			(effects
				(font
					(size 1.27 1.27)
					(thickness 0.15)
				)
				(justify left bottom)
			)
		)
		(property "Footprint" ""
			(at 177.8 109.22 0)
			(effects
				(font
					(size 1.27 1.27)
					(thickness 0.15)
				)
				(justify left bottom)
				(hide yes)
			)
		)
		(property "Datasheet" ""
			(at 177.8 114.3 0)
			(effects
				(font
					(size 1.27 1.27)
					(thickness 0.15)
				)
				(justify left bottom)
				(hide yes)
			)
		)
		(property "Description" ""
			(at 168.91 101.6 0)
			(effects
				(font
					(size 1.27 1.27)
				)
			)
		)
		(property "Author" "Antmicro"
			(at 177.8 109.22 0)
			(effects
				(font
					(size 1.27 1.27)
					(thickness 0.15)
				)
				(justify left bottom)
				(hide yes)
			)
		)
		(property "License" "Apache-2.0"
			(at 177.8 111.76 0)
			(effects
				(font
					(size 1.27 1.27)
					(thickness 0.15)
				)
				(justify left bottom)
				(hide yes)
			)
		)
		(pin "1"
		)
		(instances
			(project "lpddr4-test-board"
				(path ""
					(reference "#PWR086")
					(unit 1)
				)
			)
		)
	)
	(symbol
		(lib_id "antmicroCapacitorsmisc:C_100n_0201")
		(at 147.955 95.25 270)
		(unit 1)
		(exclude_from_sim no)
		(in_bom yes)
		(on_board yes)
		(dnp no)
		(property "Reference" "C56"
			(at 148.59 97.155 90)
			(effects
				(font
					(size 1.27 1.27)
					(thickness 0.15)
				)
				(justify left bottom)
			)
		)
		(property "Value" "C_100n_0201"
			(at 137.795 115.57 0)
			(effects
				(font
					(size 1.27 1.27)
					(thickness 0.15)
				)
				(justify left bottom)
				(hide yes)
			)
		)
		(property "Footprint" "antmicro-footprints:C_0201"
			(at 135.255 115.57 0)
			(effects
				(font
					(size 1.27 1.27)
					(thickness 0.15)
				)
				(justify left bottom)
				(hide yes)
			)
		)
		(property "Datasheet" " "
			(at 132.715 115.57 0)
			(effects
				(font
					(size 1.27 1.27)
					(thickness 0.15)
				)
				(justify left bottom)
				(hide yes)
			)
		)
		(property "Description" ""
			(at 147.955 95.25 0)
			(effects
				(font
					(size 1.27 1.27)
				)
			)
		)
		(property "Manufacturer" "Yaego"
			(at 127.635 115.57 0)
			(effects
				(font
					(size 1.27 1.27)
					(thickness 0.15)
				)
				(justify left bottom)
				(hide yes)
			)
		)
		(property "MPN" "CC0201KRX6S5BB104"
			(at 130.175 115.57 0)
			(effects
				(font
					(size 1.27 1.27)
					(thickness 0.15)
				)
				(justify left bottom)
				(hide yes)
			)
		)
		(property "Val" "100n"
			(at 148.59 100.965 90)
			(effects
				(font
					(size 1.27 1.27)
					(thickness 0.15)
				)
				(justify left bottom)
			)
		)
		(property "License" "Apache-2.0"
			(at 125.095 115.57 0)
			(effects
				(font
					(size 1.27 1.27)
					(thickness 0.15)
				)
				(justify left bottom)
				(hide yes)
			)
		)
		(property "Author" "Antmicro"
			(at 122.555 115.57 0)
			(effects
				(font
					(size 1.27 1.27)
					(thickness 0.15)
				)
				(justify left bottom)
				(hide yes)
			)
		)
		(property "Voltage" ""
			(at 120.015 115.57 0)
			(effects
				(font
					(size 1.27 1.27)
				)
				(justify left bottom)
				(hide yes)
			)
		)
		(property "Dielectric" ""
			(at 117.475 115.57 0)
			(effects
				(font
					(size 1.27 1.27)
				)
				(justify left bottom)
				(hide yes)
			)
		)
		(pin "1"
		)
		(pin "2"
		)
		(instances
			(project "lpddr4-test-board"
				(path ""
					(reference "C56")
					(unit 1)
				)
			)
		)
	)
	(symbol
		(lib_id "antmicropower:GND")
		(at 161.925 101.6 0)
		(unit 1)
		(exclude_from_sim no)
		(in_bom yes)
		(on_board yes)
		(dnp no)
		(property "Reference" "#PWR090"
			(at 170.815 104.14 0)
			(effects
				(font
					(size 1.27 1.27)
					(thickness 0.15)
				)
				(justify left bottom)
				(hide yes)
			)
		)
		(property "Value" "GND"
			(at 160.02 106.045 0)
			(effects
				(font
					(size 1.27 1.27)
					(thickness 0.15)
				)
				(justify left bottom)
			)
		)
		(property "Footprint" ""
			(at 170.815 109.22 0)
			(effects
				(font
					(size 1.27 1.27)
					(thickness 0.15)
				)
				(justify left bottom)
				(hide yes)
			)
		)
		(property "Datasheet" ""
			(at 170.815 114.3 0)
			(effects
				(font
					(size 1.27 1.27)
					(thickness 0.15)
				)
				(justify left bottom)
				(hide yes)
			)
		)
		(property "Description" ""
			(at 161.925 101.6 0)
			(effects
				(font
					(size 1.27 1.27)
				)
			)
		)
		(property "Author" "Antmicro"
			(at 170.815 109.22 0)
			(effects
				(font
					(size 1.27 1.27)
					(thickness 0.15)
				)
				(justify left bottom)
				(hide yes)
			)
		)
		(property "License" "Apache-2.0"
			(at 170.815 111.76 0)
			(effects
				(font
					(size 1.27 1.27)
					(thickness 0.15)
				)
				(justify left bottom)
				(hide yes)
			)
		)
		(pin "1"
		)
		(instances
			(project "lpddr4-test-board"
				(path ""
					(reference "#PWR090")
					(unit 1)
				)
			)
		)
	)
	(symbol
		(lib_id "antmicroCapacitorsmisc:C_100n_0201")
		(at 154.94 95.25 270)
		(unit 1)
		(exclude_from_sim no)
		(in_bom yes)
		(on_board yes)
		(dnp no)
		(property "Reference" "C59"
			(at 155.575 97.155 90)
			(effects
				(font
					(size 1.27 1.27)
					(thickness 0.15)
				)
				(justify left bottom)
			)
		)
		(property "Value" "C_100n_0201"
			(at 144.78 115.57 0)
			(effects
				(font
					(size 1.27 1.27)
					(thickness 0.15)
				)
				(justify left bottom)
				(hide yes)
			)
		)
		(property "Footprint" "antmicro-footprints:C_0201"
			(at 142.24 115.57 0)
			(effects
				(font
					(size 1.27 1.27)
					(thickness 0.15)
				)
				(justify left bottom)
				(hide yes)
			)
		)
		(property "Datasheet" " "
			(at 139.7 115.57 0)
			(effects
				(font
					(size 1.27 1.27)
					(thickness 0.15)
				)
				(justify left bottom)
				(hide yes)
			)
		)
		(property "Description" ""
			(at 154.94 95.25 0)
			(effects
				(font
					(size 1.27 1.27)
				)
			)
		)
		(property "Manufacturer" "Yaego"
			(at 134.62 115.57 0)
			(effects
				(font
					(size 1.27 1.27)
					(thickness 0.15)
				)
				(justify left bottom)
				(hide yes)
			)
		)
		(property "MPN" "CC0201KRX6S5BB104"
			(at 137.16 115.57 0)
			(effects
				(font
					(size 1.27 1.27)
					(thickness 0.15)
				)
				(justify left bottom)
				(hide yes)
			)
		)
		(property "Val" "100n"
			(at 155.575 100.965 90)
			(effects
				(font
					(size 1.27 1.27)
					(thickness 0.15)
				)
				(justify left bottom)
			)
		)
		(property "License" "Apache-2.0"
			(at 132.08 115.57 0)
			(effects
				(font
					(size 1.27 1.27)
					(thickness 0.15)
				)
				(justify left bottom)
				(hide yes)
			)
		)
		(property "Author" "Antmicro"
			(at 129.54 115.57 0)
			(effects
				(font
					(size 1.27 1.27)
					(thickness 0.15)
				)
				(justify left bottom)
				(hide yes)
			)
		)
		(property "Voltage" ""
			(at 127 115.57 0)
			(effects
				(font
					(size 1.27 1.27)
				)
				(justify left bottom)
				(hide yes)
			)
		)
		(property "Dielectric" ""
			(at 124.46 115.57 0)
			(effects
				(font
					(size 1.27 1.27)
				)
				(justify left bottom)
				(hide yes)
			)
		)
		(pin "1"
		)
		(pin "2"
		)
		(instances
			(project "lpddr4-test-board"
				(path ""
					(reference "C59")
					(unit 1)
				)
			)
		)
	)
	(symbol
		(lib_id "antmicropower:GND")
		(at 154.94 101.6 0)
		(unit 1)
		(exclude_from_sim no)
		(in_bom yes)
		(on_board yes)
		(dnp no)
		(property "Reference" "#PWR093"
			(at 163.83 104.14 0)
			(effects
				(font
					(size 1.27 1.27)
					(thickness 0.15)
				)
				(justify left bottom)
				(hide yes)
			)
		)
		(property "Value" "GND"
			(at 153.035 106.045 0)
			(effects
				(font
					(size 1.27 1.27)
					(thickness 0.15)
				)
				(justify left bottom)
			)
		)
		(property "Footprint" ""
			(at 163.83 109.22 0)
			(effects
				(font
					(size 1.27 1.27)
					(thickness 0.15)
				)
				(justify left bottom)
				(hide yes)
			)
		)
		(property "Datasheet" ""
			(at 163.83 114.3 0)
			(effects
				(font
					(size 1.27 1.27)
					(thickness 0.15)
				)
				(justify left bottom)
				(hide yes)
			)
		)
		(property "Description" ""
			(at 154.94 101.6 0)
			(effects
				(font
					(size 1.27 1.27)
				)
			)
		)
		(property "Author" "Antmicro"
			(at 163.83 109.22 0)
			(effects
				(font
					(size 1.27 1.27)
					(thickness 0.15)
				)
				(justify left bottom)
				(hide yes)
			)
		)
		(property "License" "Apache-2.0"
			(at 163.83 111.76 0)
			(effects
				(font
					(size 1.27 1.27)
					(thickness 0.15)
				)
				(justify left bottom)
				(hide yes)
			)
		)
		(pin "1"
		)
		(instances
			(project "lpddr4-test-board"
				(path ""
					(reference "#PWR093")
					(unit 1)
				)
			)
		)
	)
	(symbol
		(lib_id "antmicroCapacitors0402:C_4u7_0402")
		(at 182.88 228.6 270)
		(unit 1)
		(exclude_from_sim no)
		(in_bom yes)
		(on_board yes)
		(dnp no)
		(property "Reference" "C82"
			(at 183.515 230.505 90)
			(effects
				(font
					(size 1.27 1.27)
					(thickness 0.15)
				)
				(justify left bottom)
			)
		)
		(property "Value" "C_4u7_0402"
			(at 172.72 248.92 0)
			(effects
				(font
					(size 1.27 1.27)
					(thickness 0.15)
				)
				(justify left bottom)
				(hide yes)
			)
		)
		(property "Footprint" "antmicro-footprints:C_0402_1005Metric"
			(at 170.18 248.92 0)
			(effects
				(font
					(size 1.27 1.27)
					(thickness 0.15)
				)
				(justify left bottom)
				(hide yes)
			)
		)
		(property "Datasheet" " "
			(at 167.64 248.92 0)
			(effects
				(font
					(size 1.27 1.27)
					(thickness 0.15)
				)
				(justify left bottom)
				(hide yes)
			)
		)
		(property "Description" ""
			(at 182.88 228.6 0)
			(effects
				(font
					(size 1.27 1.27)
				)
			)
		)
		(property "Manufacturer" "Murata"
			(at 162.56 248.92 0)
			(effects
				(font
					(size 1.27 1.27)
					(thickness 0.15)
				)
				(justify left bottom)
				(hide yes)
			)
		)
		(property "MPN" "GRM155R61A475MEAAD"
			(at 165.1 248.92 0)
			(effects
				(font
					(size 1.27 1.27)
					(thickness 0.15)
				)
				(justify left bottom)
				(hide yes)
			)
		)
		(property "Val" "4u7"
			(at 183.515 234.315 90)
			(effects
				(font
					(size 1.27 1.27)
					(thickness 0.15)
				)
				(justify left bottom)
			)
		)
		(property "License" "Apache-2.0"
			(at 160.02 248.92 0)
			(effects
				(font
					(size 1.27 1.27)
					(thickness 0.15)
				)
				(justify left bottom)
				(hide yes)
			)
		)
		(property "Author" "Antmicro"
			(at 157.48 248.92 0)
			(effects
				(font
					(size 1.27 1.27)
					(thickness 0.15)
				)
				(justify left bottom)
				(hide yes)
			)
		)
		(property "Voltage" ""
			(at 154.94 248.92 0)
			(effects
				(font
					(size 1.27 1.27)
				)
				(justify left bottom)
				(hide yes)
			)
		)
		(property "Dielectric" ""
			(at 152.4 248.92 0)
			(effects
				(font
					(size 1.27 1.27)
				)
				(justify left bottom)
				(hide yes)
			)
		)
		(pin "1"
		)
		(pin "2"
		)
		(instances
			(project "lpddr4-test-board"
				(path ""
					(reference "C82")
					(unit 1)
				)
			)
		)
	)
	(symbol
		(lib_id "antmicroCapacitorsmisc:C_100n_0201")
		(at 161.925 95.25 270)
		(unit 1)
		(exclude_from_sim no)
		(in_bom yes)
		(on_board yes)
		(dnp no)
		(property "Reference" "C62"
			(at 162.56 97.155 90)
			(effects
				(font
					(size 1.27 1.27)
					(thickness 0.15)
				)
				(justify left bottom)
			)
		)
		(property "Value" "C_100n_0201"
			(at 151.765 115.57 0)
			(effects
				(font
					(size 1.27 1.27)
					(thickness 0.15)
				)
				(justify left bottom)
				(hide yes)
			)
		)
		(property "Footprint" "antmicro-footprints:C_0201"
			(at 149.225 115.57 0)
			(effects
				(font
					(size 1.27 1.27)
					(thickness 0.15)
				)
				(justify left bottom)
				(hide yes)
			)
		)
		(property "Datasheet" " "
			(at 146.685 115.57 0)
			(effects
				(font
					(size 1.27 1.27)
					(thickness 0.15)
				)
				(justify left bottom)
				(hide yes)
			)
		)
		(property "Description" ""
			(at 161.925 95.25 0)
			(effects
				(font
					(size 1.27 1.27)
				)
			)
		)
		(property "Manufacturer" "Yaego"
			(at 141.605 115.57 0)
			(effects
				(font
					(size 1.27 1.27)
					(thickness 0.15)
				)
				(justify left bottom)
				(hide yes)
			)
		)
		(property "MPN" "CC0201KRX6S5BB104"
			(at 144.145 115.57 0)
			(effects
				(font
					(size 1.27 1.27)
					(thickness 0.15)
				)
				(justify left bottom)
				(hide yes)
			)
		)
		(property "Val" "100n"
			(at 162.56 100.965 90)
			(effects
				(font
					(size 1.27 1.27)
					(thickness 0.15)
				)
				(justify left bottom)
			)
		)
		(property "License" "Apache-2.0"
			(at 139.065 115.57 0)
			(effects
				(font
					(size 1.27 1.27)
					(thickness 0.15)
				)
				(justify left bottom)
				(hide yes)
			)
		)
		(property "Author" "Antmicro"
			(at 136.525 115.57 0)
			(effects
				(font
					(size 1.27 1.27)
					(thickness 0.15)
				)
				(justify left bottom)
				(hide yes)
			)
		)
		(property "Voltage" ""
			(at 133.985 115.57 0)
			(effects
				(font
					(size 1.27 1.27)
				)
				(justify left bottom)
				(hide yes)
			)
		)
		(property "Dielectric" ""
			(at 131.445 115.57 0)
			(effects
				(font
					(size 1.27 1.27)
				)
				(justify left bottom)
				(hide yes)
			)
		)
		(pin "1"
		)
		(pin "2"
		)
		(instances
			(project "lpddr4-test-board"
				(path ""
					(reference "C62")
					(unit 1)
				)
			)
		)
	)
	(symbol
		(lib_id "antmicropower:GND")
		(at 147.955 101.6 0)
		(unit 1)
		(exclude_from_sim no)
		(in_bom yes)
		(on_board yes)
		(dnp no)
		(property "Reference" "#PWR096"
			(at 156.845 104.14 0)
			(effects
				(font
					(size 1.27 1.27)
					(thickness 0.15)
				)
				(justify left bottom)
				(hide yes)
			)
		)
		(property "Value" "GND"
			(at 146.05 106.045 0)
			(effects
				(font
					(size 1.27 1.27)
					(thickness 0.15)
				)
				(justify left bottom)
			)
		)
		(property "Footprint" ""
			(at 156.845 109.22 0)
			(effects
				(font
					(size 1.27 1.27)
					(thickness 0.15)
				)
				(justify left bottom)
				(hide yes)
			)
		)
		(property "Datasheet" ""
			(at 156.845 114.3 0)
			(effects
				(font
					(size 1.27 1.27)
					(thickness 0.15)
				)
				(justify left bottom)
				(hide yes)
			)
		)
		(property "Description" ""
			(at 147.955 101.6 0)
			(effects
				(font
					(size 1.27 1.27)
				)
			)
		)
		(property "Author" "Antmicro"
			(at 156.845 109.22 0)
			(effects
				(font
					(size 1.27 1.27)
					(thickness 0.15)
				)
				(justify left bottom)
				(hide yes)
			)
		)
		(property "License" "Apache-2.0"
			(at 156.845 111.76 0)
			(effects
				(font
					(size 1.27 1.27)
					(thickness 0.15)
				)
				(justify left bottom)
				(hide yes)
			)
		)
		(pin "1"
		)
		(instances
			(project "lpddr4-test-board"
				(path ""
					(reference "#PWR096")
					(unit 1)
				)
			)
		)
	)
	(symbol
		(lib_id "antmicroCapacitorsmisc:C_100n_0201")
		(at 168.91 95.25 270)
		(unit 1)
		(exclude_from_sim no)
		(in_bom yes)
		(on_board yes)
		(dnp no)
		(property "Reference" "C66"
			(at 169.545 97.155 90)
			(effects
				(font
					(size 1.27 1.27)
					(thickness 0.15)
				)
				(justify left bottom)
			)
		)
		(property "Value" "C_100n_0201"
			(at 158.75 115.57 0)
			(effects
				(font
					(size 1.27 1.27)
					(thickness 0.15)
				)
				(justify left bottom)
				(hide yes)
			)
		)
		(property "Footprint" "antmicro-footprints:C_0201"
			(at 156.21 115.57 0)
			(effects
				(font
					(size 1.27 1.27)
					(thickness 0.15)
				)
				(justify left bottom)
				(hide yes)
			)
		)
		(property "Datasheet" " "
			(at 153.67 115.57 0)
			(effects
				(font
					(size 1.27 1.27)
					(thickness 0.15)
				)
				(justify left bottom)
				(hide yes)
			)
		)
		(property "Description" ""
			(at 168.91 95.25 0)
			(effects
				(font
					(size 1.27 1.27)
				)
			)
		)
		(property "Manufacturer" "Yaego"
			(at 148.59 115.57 0)
			(effects
				(font
					(size 1.27 1.27)
					(thickness 0.15)
				)
				(justify left bottom)
				(hide yes)
			)
		)
		(property "MPN" "CC0201KRX6S5BB104"
			(at 151.13 115.57 0)
			(effects
				(font
					(size 1.27 1.27)
					(thickness 0.15)
				)
				(justify left bottom)
				(hide yes)
			)
		)
		(property "Val" "100n"
			(at 169.545 100.965 90)
			(effects
				(font
					(size 1.27 1.27)
					(thickness 0.15)
				)
				(justify left bottom)
			)
		)
		(property "License" "Apache-2.0"
			(at 146.05 115.57 0)
			(effects
				(font
					(size 1.27 1.27)
					(thickness 0.15)
				)
				(justify left bottom)
				(hide yes)
			)
		)
		(property "Author" "Antmicro"
			(at 143.51 115.57 0)
			(effects
				(font
					(size 1.27 1.27)
					(thickness 0.15)
				)
				(justify left bottom)
				(hide yes)
			)
		)
		(property "Voltage" ""
			(at 140.97 115.57 0)
			(effects
				(font
					(size 1.27 1.27)
				)
				(justify left bottom)
				(hide yes)
			)
		)
		(property "Dielectric" ""
			(at 138.43 115.57 0)
			(effects
				(font
					(size 1.27 1.27)
				)
				(justify left bottom)
				(hide yes)
			)
		)
		(pin "1"
		)
		(pin "2"
		)
		(instances
			(project "lpddr4-test-board"
				(path ""
					(reference "C66")
					(unit 1)
				)
			)
		)
	)
	(symbol
		(lib_id "antmicropower:GND")
		(at 140.97 101.6 0)
		(unit 1)
		(exclude_from_sim no)
		(in_bom yes)
		(on_board yes)
		(dnp no)
		(property "Reference" "#PWR0100"
			(at 149.86 104.14 0)
			(effects
				(font
					(size 1.27 1.27)
					(thickness 0.15)
				)
				(justify left bottom)
				(hide yes)
			)
		)
		(property "Value" "GND"
			(at 139.065 106.045 0)
			(effects
				(font
					(size 1.27 1.27)
					(thickness 0.15)
				)
				(justify left bottom)
			)
		)
		(property "Footprint" ""
			(at 149.86 109.22 0)
			(effects
				(font
					(size 1.27 1.27)
					(thickness 0.15)
				)
				(justify left bottom)
				(hide yes)
			)
		)
		(property "Datasheet" ""
			(at 149.86 114.3 0)
			(effects
				(font
					(size 1.27 1.27)
					(thickness 0.15)
				)
				(justify left bottom)
				(hide yes)
			)
		)
		(property "Description" ""
			(at 140.97 101.6 0)
			(effects
				(font
					(size 1.27 1.27)
				)
			)
		)
		(property "Author" "Antmicro"
			(at 149.86 109.22 0)
			(effects
				(font
					(size 1.27 1.27)
					(thickness 0.15)
				)
				(justify left bottom)
				(hide yes)
			)
		)
		(property "License" "Apache-2.0"
			(at 149.86 111.76 0)
			(effects
				(font
					(size 1.27 1.27)
					(thickness 0.15)
				)
				(justify left bottom)
				(hide yes)
			)
		)
		(pin "1"
		)
		(instances
			(project "lpddr4-test-board"
				(path ""
					(reference "#PWR0100")
					(unit 1)
				)
			)
		)
	)
	(symbol
		(lib_id "antmicroCapacitorsmisc:C_100n_0201")
		(at 175.895 95.25 270)
		(unit 1)
		(exclude_from_sim no)
		(in_bom yes)
		(on_board yes)
		(dnp no)
		(property "Reference" "C70"
			(at 176.53 97.155 90)
			(effects
				(font
					(size 1.27 1.27)
					(thickness 0.15)
				)
				(justify left bottom)
			)
		)
		(property "Value" "C_100n_0201"
			(at 165.735 115.57 0)
			(effects
				(font
					(size 1.27 1.27)
					(thickness 0.15)
				)
				(justify left bottom)
				(hide yes)
			)
		)
		(property "Footprint" "antmicro-footprints:C_0201"
			(at 163.195 115.57 0)
			(effects
				(font
					(size 1.27 1.27)
					(thickness 0.15)
				)
				(justify left bottom)
				(hide yes)
			)
		)
		(property "Datasheet" " "
			(at 160.655 115.57 0)
			(effects
				(font
					(size 1.27 1.27)
					(thickness 0.15)
				)
				(justify left bottom)
				(hide yes)
			)
		)
		(property "Description" ""
			(at 175.895 95.25 0)
			(effects
				(font
					(size 1.27 1.27)
				)
			)
		)
		(property "Manufacturer" "Yaego"
			(at 155.575 115.57 0)
			(effects
				(font
					(size 1.27 1.27)
					(thickness 0.15)
				)
				(justify left bottom)
				(hide yes)
			)
		)
		(property "MPN" "CC0201KRX6S5BB104"
			(at 158.115 115.57 0)
			(effects
				(font
					(size 1.27 1.27)
					(thickness 0.15)
				)
				(justify left bottom)
				(hide yes)
			)
		)
		(property "Val" "100n"
			(at 176.53 100.965 90)
			(effects
				(font
					(size 1.27 1.27)
					(thickness 0.15)
				)
				(justify left bottom)
			)
		)
		(property "License" "Apache-2.0"
			(at 153.035 115.57 0)
			(effects
				(font
					(size 1.27 1.27)
					(thickness 0.15)
				)
				(justify left bottom)
				(hide yes)
			)
		)
		(property "Author" "Antmicro"
			(at 150.495 115.57 0)
			(effects
				(font
					(size 1.27 1.27)
					(thickness 0.15)
				)
				(justify left bottom)
				(hide yes)
			)
		)
		(property "Voltage" ""
			(at 147.955 115.57 0)
			(effects
				(font
					(size 1.27 1.27)
				)
				(justify left bottom)
				(hide yes)
			)
		)
		(property "Dielectric" ""
			(at 145.415 115.57 0)
			(effects
				(font
					(size 1.27 1.27)
				)
				(justify left bottom)
				(hide yes)
			)
		)
		(pin "1"
		)
		(pin "2"
		)
		(instances
			(project "lpddr4-test-board"
				(path ""
					(reference "C70")
					(unit 1)
				)
			)
		)
	)
	(symbol
		(lib_id "antmicropower:GND")
		(at 133.985 101.6 0)
		(unit 1)
		(exclude_from_sim no)
		(in_bom yes)
		(on_board yes)
		(dnp no)
		(property "Reference" "#PWR0104"
			(at 142.875 104.14 0)
			(effects
				(font
					(size 1.27 1.27)
					(thickness 0.15)
				)
				(justify left bottom)
				(hide yes)
			)
		)
		(property "Value" "GND"
			(at 132.08 106.045 0)
			(effects
				(font
					(size 1.27 1.27)
					(thickness 0.15)
				)
				(justify left bottom)
			)
		)
		(property "Footprint" ""
			(at 142.875 109.22 0)
			(effects
				(font
					(size 1.27 1.27)
					(thickness 0.15)
				)
				(justify left bottom)
				(hide yes)
			)
		)
		(property "Datasheet" ""
			(at 142.875 114.3 0)
			(effects
				(font
					(size 1.27 1.27)
					(thickness 0.15)
				)
				(justify left bottom)
				(hide yes)
			)
		)
		(property "Description" ""
			(at 133.985 101.6 0)
			(effects
				(font
					(size 1.27 1.27)
				)
			)
		)
		(property "Author" "Antmicro"
			(at 142.875 109.22 0)
			(effects
				(font
					(size 1.27 1.27)
					(thickness 0.15)
				)
				(justify left bottom)
				(hide yes)
			)
		)
		(property "License" "Apache-2.0"
			(at 142.875 111.76 0)
			(effects
				(font
					(size 1.27 1.27)
					(thickness 0.15)
				)
				(justify left bottom)
				(hide yes)
			)
		)
		(pin "1"
		)
		(instances
			(project "lpddr4-test-board"
				(path ""
					(reference "#PWR0104")
					(unit 1)
				)
			)
		)
	)
	(symbol
		(lib_id "antmicroCapacitorsmisc:C_100n_0201")
		(at 182.88 95.25 270)
		(unit 1)
		(exclude_from_sim no)
		(in_bom yes)
		(on_board yes)
		(dnp no)
		(property "Reference" "C74"
			(at 183.515 97.155 90)
			(effects
				(font
					(size 1.27 1.27)
					(thickness 0.15)
				)
				(justify left bottom)
			)
		)
		(property "Value" "C_100n_0201"
			(at 172.72 115.57 0)
			(effects
				(font
					(size 1.27 1.27)
					(thickness 0.15)
				)
				(justify left bottom)
				(hide yes)
			)
		)
		(property "Footprint" "antmicro-footprints:C_0201"
			(at 170.18 115.57 0)
			(effects
				(font
					(size 1.27 1.27)
					(thickness 0.15)
				)
				(justify left bottom)
				(hide yes)
			)
		)
		(property "Datasheet" " "
			(at 167.64 115.57 0)
			(effects
				(font
					(size 1.27 1.27)
					(thickness 0.15)
				)
				(justify left bottom)
				(hide yes)
			)
		)
		(property "Description" ""
			(at 182.88 95.25 0)
			(effects
				(font
					(size 1.27 1.27)
				)
			)
		)
		(property "Manufacturer" "Yaego"
			(at 162.56 115.57 0)
			(effects
				(font
					(size 1.27 1.27)
					(thickness 0.15)
				)
				(justify left bottom)
				(hide yes)
			)
		)
		(property "MPN" "CC0201KRX6S5BB104"
			(at 165.1 115.57 0)
			(effects
				(font
					(size 1.27 1.27)
					(thickness 0.15)
				)
				(justify left bottom)
				(hide yes)
			)
		)
		(property "Val" "100n"
			(at 183.515 100.965 90)
			(effects
				(font
					(size 1.27 1.27)
					(thickness 0.15)
				)
				(justify left bottom)
			)
		)
		(property "License" "Apache-2.0"
			(at 160.02 115.57 0)
			(effects
				(font
					(size 1.27 1.27)
					(thickness 0.15)
				)
				(justify left bottom)
				(hide yes)
			)
		)
		(property "Author" "Antmicro"
			(at 157.48 115.57 0)
			(effects
				(font
					(size 1.27 1.27)
					(thickness 0.15)
				)
				(justify left bottom)
				(hide yes)
			)
		)
		(property "Voltage" ""
			(at 154.94 115.57 0)
			(effects
				(font
					(size 1.27 1.27)
				)
				(justify left bottom)
				(hide yes)
			)
		)
		(property "Dielectric" ""
			(at 152.4 115.57 0)
			(effects
				(font
					(size 1.27 1.27)
				)
				(justify left bottom)
				(hide yes)
			)
		)
		(pin "1"
		)
		(pin "2"
		)
		(instances
			(project "lpddr4-test-board"
				(path ""
					(reference "C74")
					(unit 1)
				)
			)
		)
	)
	(symbol
		(lib_id "antmicropower:GND")
		(at 127 101.6 0)
		(unit 1)
		(exclude_from_sim no)
		(in_bom yes)
		(on_board yes)
		(dnp no)
		(property "Reference" "#PWR0108"
			(at 135.89 104.14 0)
			(effects
				(font
					(size 1.27 1.27)
					(thickness 0.15)
				)
				(justify left bottom)
				(hide yes)
			)
		)
		(property "Value" "GND"
			(at 125.095 106.045 0)
			(effects
				(font
					(size 1.27 1.27)
					(thickness 0.15)
				)
				(justify left bottom)
			)
		)
		(property "Footprint" ""
			(at 135.89 109.22 0)
			(effects
				(font
					(size 1.27 1.27)
					(thickness 0.15)
				)
				(justify left bottom)
				(hide yes)
			)
		)
		(property "Datasheet" ""
			(at 135.89 114.3 0)
			(effects
				(font
					(size 1.27 1.27)
					(thickness 0.15)
				)
				(justify left bottom)
				(hide yes)
			)
		)
		(property "Description" ""
			(at 127 101.6 0)
			(effects
				(font
					(size 1.27 1.27)
				)
			)
		)
		(property "Author" "Antmicro"
			(at 135.89 109.22 0)
			(effects
				(font
					(size 1.27 1.27)
					(thickness 0.15)
				)
				(justify left bottom)
				(hide yes)
			)
		)
		(property "License" "Apache-2.0"
			(at 135.89 111.76 0)
			(effects
				(font
					(size 1.27 1.27)
					(thickness 0.15)
				)
				(justify left bottom)
				(hide yes)
			)
		)
		(pin "1"
		)
		(instances
			(project "lpddr4-test-board"
				(path ""
					(reference "#PWR0108")
					(unit 1)
				)
			)
		)
	)
	(symbol
		(lib_id "antmicroCapacitors0402:C_4u7_0402")
		(at 189.865 228.6 270)
		(unit 1)
		(exclude_from_sim no)
		(in_bom yes)
		(on_board yes)
		(dnp no)
		(property "Reference" "C85"
			(at 190.5 230.505 90)
			(effects
				(font
					(size 1.27 1.27)
					(thickness 0.15)
				)
				(justify left bottom)
			)
		)
		(property "Value" "C_4u7_0402"
			(at 179.705 248.92 0)
			(effects
				(font
					(size 1.27 1.27)
					(thickness 0.15)
				)
				(justify left bottom)
				(hide yes)
			)
		)
		(property "Footprint" "antmicro-footprints:C_0402_1005Metric"
			(at 177.165 248.92 0)
			(effects
				(font
					(size 1.27 1.27)
					(thickness 0.15)
				)
				(justify left bottom)
				(hide yes)
			)
		)
		(property "Datasheet" " "
			(at 174.625 248.92 0)
			(effects
				(font
					(size 1.27 1.27)
					(thickness 0.15)
				)
				(justify left bottom)
				(hide yes)
			)
		)
		(property "Description" ""
			(at 189.865 228.6 0)
			(effects
				(font
					(size 1.27 1.27)
				)
			)
		)
		(property "Manufacturer" "Murata"
			(at 169.545 248.92 0)
			(effects
				(font
					(size 1.27 1.27)
					(thickness 0.15)
				)
				(justify left bottom)
				(hide yes)
			)
		)
		(property "MPN" "GRM155R61A475MEAAD"
			(at 172.085 248.92 0)
			(effects
				(font
					(size 1.27 1.27)
					(thickness 0.15)
				)
				(justify left bottom)
				(hide yes)
			)
		)
		(property "Val" "4u7"
			(at 190.5 234.315 90)
			(effects
				(font
					(size 1.27 1.27)
					(thickness 0.15)
				)
				(justify left bottom)
			)
		)
		(property "License" "Apache-2.0"
			(at 167.005 248.92 0)
			(effects
				(font
					(size 1.27 1.27)
					(thickness 0.15)
				)
				(justify left bottom)
				(hide yes)
			)
		)
		(property "Author" "Antmicro"
			(at 164.465 248.92 0)
			(effects
				(font
					(size 1.27 1.27)
					(thickness 0.15)
				)
				(justify left bottom)
				(hide yes)
			)
		)
		(property "Voltage" ""
			(at 161.925 248.92 0)
			(effects
				(font
					(size 1.27 1.27)
				)
				(justify left bottom)
				(hide yes)
			)
		)
		(property "Dielectric" ""
			(at 159.385 248.92 0)
			(effects
				(font
					(size 1.27 1.27)
				)
				(justify left bottom)
				(hide yes)
			)
		)
		(pin "1"
		)
		(pin "2"
		)
		(instances
			(project "lpddr4-test-board"
				(path ""
					(reference "C85")
					(unit 1)
				)
			)
		)
	)
	(symbol
		(lib_id "antmicroCapacitors0402:C_4u7_0402")
		(at 196.85 228.6 270)
		(unit 1)
		(exclude_from_sim no)
		(in_bom yes)
		(on_board yes)
		(dnp no)
		(property "Reference" "C87"
			(at 197.485 230.505 90)
			(effects
				(font
					(size 1.27 1.27)
					(thickness 0.15)
				)
				(justify left bottom)
			)
		)
		(property "Value" "C_4u7_0402"
			(at 186.69 248.92 0)
			(effects
				(font
					(size 1.27 1.27)
					(thickness 0.15)
				)
				(justify left bottom)
				(hide yes)
			)
		)
		(property "Footprint" "antmicro-footprints:C_0402_1005Metric"
			(at 184.15 248.92 0)
			(effects
				(font
					(size 1.27 1.27)
					(thickness 0.15)
				)
				(justify left bottom)
				(hide yes)
			)
		)
		(property "Datasheet" " "
			(at 181.61 248.92 0)
			(effects
				(font
					(size 1.27 1.27)
					(thickness 0.15)
				)
				(justify left bottom)
				(hide yes)
			)
		)
		(property "Description" ""
			(at 196.85 228.6 0)
			(effects
				(font
					(size 1.27 1.27)
				)
			)
		)
		(property "Manufacturer" "Murata"
			(at 176.53 248.92 0)
			(effects
				(font
					(size 1.27 1.27)
					(thickness 0.15)
				)
				(justify left bottom)
				(hide yes)
			)
		)
		(property "MPN" "GRM155R61A475MEAAD"
			(at 179.07 248.92 0)
			(effects
				(font
					(size 1.27 1.27)
					(thickness 0.15)
				)
				(justify left bottom)
				(hide yes)
			)
		)
		(property "Val" "4u7"
			(at 197.485 234.315 90)
			(effects
				(font
					(size 1.27 1.27)
					(thickness 0.15)
				)
				(justify left bottom)
			)
		)
		(property "License" "Apache-2.0"
			(at 173.99 248.92 0)
			(effects
				(font
					(size 1.27 1.27)
					(thickness 0.15)
				)
				(justify left bottom)
				(hide yes)
			)
		)
		(property "Author" "Antmicro"
			(at 171.45 248.92 0)
			(effects
				(font
					(size 1.27 1.27)
					(thickness 0.15)
				)
				(justify left bottom)
				(hide yes)
			)
		)
		(property "Voltage" ""
			(at 168.91 248.92 0)
			(effects
				(font
					(size 1.27 1.27)
				)
				(justify left bottom)
				(hide yes)
			)
		)
		(property "Dielectric" ""
			(at 166.37 248.92 0)
			(effects
				(font
					(size 1.27 1.27)
				)
				(justify left bottom)
				(hide yes)
			)
		)
		(pin "1"
		)
		(pin "2"
		)
		(instances
			(project "lpddr4-test-board"
				(path ""
					(reference "C87")
					(unit 1)
				)
			)
		)
	)
	(symbol
		(lib_id "antmicroCapacitors0402:C_4u7_0402")
		(at 203.835 228.6 270)
		(unit 1)
		(exclude_from_sim no)
		(in_bom yes)
		(on_board yes)
		(dnp no)
		(property "Reference" "C89"
			(at 204.47 230.505 90)
			(effects
				(font
					(size 1.27 1.27)
					(thickness 0.15)
				)
				(justify left bottom)
			)
		)
		(property "Value" "C_4u7_0402"
			(at 193.675 248.92 0)
			(effects
				(font
					(size 1.27 1.27)
					(thickness 0.15)
				)
				(justify left bottom)
				(hide yes)
			)
		)
		(property "Footprint" "antmicro-footprints:C_0402_1005Metric"
			(at 191.135 248.92 0)
			(effects
				(font
					(size 1.27 1.27)
					(thickness 0.15)
				)
				(justify left bottom)
				(hide yes)
			)
		)
		(property "Datasheet" " "
			(at 188.595 248.92 0)
			(effects
				(font
					(size 1.27 1.27)
					(thickness 0.15)
				)
				(justify left bottom)
				(hide yes)
			)
		)
		(property "Description" ""
			(at 203.835 228.6 0)
			(effects
				(font
					(size 1.27 1.27)
				)
			)
		)
		(property "Manufacturer" "Murata"
			(at 183.515 248.92 0)
			(effects
				(font
					(size 1.27 1.27)
					(thickness 0.15)
				)
				(justify left bottom)
				(hide yes)
			)
		)
		(property "MPN" "GRM155R61A475MEAAD"
			(at 186.055 248.92 0)
			(effects
				(font
					(size 1.27 1.27)
					(thickness 0.15)
				)
				(justify left bottom)
				(hide yes)
			)
		)
		(property "Val" "4u7"
			(at 204.47 234.315 90)
			(effects
				(font
					(size 1.27 1.27)
					(thickness 0.15)
				)
				(justify left bottom)
			)
		)
		(property "License" "Apache-2.0"
			(at 180.975 248.92 0)
			(effects
				(font
					(size 1.27 1.27)
					(thickness 0.15)
				)
				(justify left bottom)
				(hide yes)
			)
		)
		(property "Author" "Antmicro"
			(at 178.435 248.92 0)
			(effects
				(font
					(size 1.27 1.27)
					(thickness 0.15)
				)
				(justify left bottom)
				(hide yes)
			)
		)
		(property "Voltage" ""
			(at 175.895 248.92 0)
			(effects
				(font
					(size 1.27 1.27)
				)
				(justify left bottom)
				(hide yes)
			)
		)
		(property "Dielectric" ""
			(at 173.355 248.92 0)
			(effects
				(font
					(size 1.27 1.27)
				)
				(justify left bottom)
				(hide yes)
			)
		)
		(pin "1"
		)
		(pin "2"
		)
		(instances
			(project "lpddr4-test-board"
				(path ""
					(reference "C89")
					(unit 1)
				)
			)
		)
	)
	(symbol
		(lib_id "antmicropower:GND")
		(at 312.42 168.91 0)
		(unit 1)
		(exclude_from_sim no)
		(in_bom yes)
		(on_board yes)
		(dnp no)
		(property "Reference" "#PWR0127"
			(at 321.31 171.45 0)
			(effects
				(font
					(size 1.27 1.27)
					(thickness 0.15)
				)
				(justify left bottom)
				(hide yes)
			)
		)
		(property "Value" "GND"
			(at 310.515 173.355 0)
			(effects
				(font
					(size 1.27 1.27)
					(thickness 0.15)
				)
				(justify left bottom)
			)
		)
		(property "Footprint" ""
			(at 321.31 176.53 0)
			(effects
				(font
					(size 1.27 1.27)
					(thickness 0.15)
				)
				(justify left bottom)
				(hide yes)
			)
		)
		(property "Datasheet" ""
			(at 321.31 181.61 0)
			(effects
				(font
					(size 1.27 1.27)
					(thickness 0.15)
				)
				(justify left bottom)
				(hide yes)
			)
		)
		(property "Description" ""
			(at 312.42 168.91 0)
			(effects
				(font
					(size 1.27 1.27)
				)
			)
		)
		(property "Author" "Antmicro"
			(at 321.31 176.53 0)
			(effects
				(font
					(size 1.27 1.27)
					(thickness 0.15)
				)
				(justify left bottom)
				(hide yes)
			)
		)
		(property "License" "Apache-2.0"
			(at 321.31 179.07 0)
			(effects
				(font
					(size 1.27 1.27)
					(thickness 0.15)
				)
				(justify left bottom)
				(hide yes)
			)
		)
		(pin "1"
		)
		(instances
			(project "lpddr4-test-board"
				(path ""
					(reference "#PWR0127")
					(unit 1)
				)
			)
		)
	)
	(symbol
		(lib_id "antmicroCapacitors0402:C_4u7_0402")
		(at 210.82 228.6 270)
		(unit 1)
		(exclude_from_sim no)
		(in_bom yes)
		(on_board yes)
		(dnp no)
		(property "Reference" "C91"
			(at 211.455 230.505 90)
			(effects
				(font
					(size 1.27 1.27)
					(thickness 0.15)
				)
				(justify left bottom)
			)
		)
		(property "Value" "C_4u7_0402"
			(at 200.66 248.92 0)
			(effects
				(font
					(size 1.27 1.27)
					(thickness 0.15)
				)
				(justify left bottom)
				(hide yes)
			)
		)
		(property "Footprint" "antmicro-footprints:C_0402_1005Metric"
			(at 198.12 248.92 0)
			(effects
				(font
					(size 1.27 1.27)
					(thickness 0.15)
				)
				(justify left bottom)
				(hide yes)
			)
		)
		(property "Datasheet" " "
			(at 195.58 248.92 0)
			(effects
				(font
					(size 1.27 1.27)
					(thickness 0.15)
				)
				(justify left bottom)
				(hide yes)
			)
		)
		(property "Description" ""
			(at 210.82 228.6 0)
			(effects
				(font
					(size 1.27 1.27)
				)
			)
		)
		(property "Manufacturer" "Murata"
			(at 190.5 248.92 0)
			(effects
				(font
					(size 1.27 1.27)
					(thickness 0.15)
				)
				(justify left bottom)
				(hide yes)
			)
		)
		(property "MPN" "GRM155R61A475MEAAD"
			(at 193.04 248.92 0)
			(effects
				(font
					(size 1.27 1.27)
					(thickness 0.15)
				)
				(justify left bottom)
				(hide yes)
			)
		)
		(property "Val" "4u7"
			(at 211.455 234.315 90)
			(effects
				(font
					(size 1.27 1.27)
					(thickness 0.15)
				)
				(justify left bottom)
			)
		)
		(property "License" "Apache-2.0"
			(at 187.96 248.92 0)
			(effects
				(font
					(size 1.27 1.27)
					(thickness 0.15)
				)
				(justify left bottom)
				(hide yes)
			)
		)
		(property "Author" "Antmicro"
			(at 185.42 248.92 0)
			(effects
				(font
					(size 1.27 1.27)
					(thickness 0.15)
				)
				(justify left bottom)
				(hide yes)
			)
		)
		(property "Voltage" ""
			(at 182.88 248.92 0)
			(effects
				(font
					(size 1.27 1.27)
				)
				(justify left bottom)
				(hide yes)
			)
		)
		(property "Dielectric" ""
			(at 180.34 248.92 0)
			(effects
				(font
					(size 1.27 1.27)
				)
				(justify left bottom)
				(hide yes)
			)
		)
		(pin "1"
		)
		(pin "2"
		)
		(instances
			(project "lpddr4-test-board"
				(path ""
					(reference "C91")
					(unit 1)
				)
			)
		)
	)
	(symbol
		(lib_id "antmicroCapacitorsmisc:C_100n_0201")
		(at 140.97 133.35 270)
		(unit 1)
		(exclude_from_sim no)
		(in_bom yes)
		(on_board yes)
		(dnp no)
		(property "Reference" "C71"
			(at 141.605 135.255 90)
			(effects
				(font
					(size 1.27 1.27)
					(thickness 0.15)
				)
				(justify left bottom)
			)
		)
		(property "Value" "C_100n_0201"
			(at 130.81 153.67 0)
			(effects
				(font
					(size 1.27 1.27)
					(thickness 0.15)
				)
				(justify left bottom)
				(hide yes)
			)
		)
		(property "Footprint" "antmicro-footprints:C_0201"
			(at 128.27 153.67 0)
			(effects
				(font
					(size 1.27 1.27)
					(thickness 0.15)
				)
				(justify left bottom)
				(hide yes)
			)
		)
		(property "Datasheet" " "
			(at 125.73 153.67 0)
			(effects
				(font
					(size 1.27 1.27)
					(thickness 0.15)
				)
				(justify left bottom)
				(hide yes)
			)
		)
		(property "Description" ""
			(at 140.97 133.35 0)
			(effects
				(font
					(size 1.27 1.27)
				)
			)
		)
		(property "Manufacturer" "Yaego"
			(at 120.65 153.67 0)
			(effects
				(font
					(size 1.27 1.27)
					(thickness 0.15)
				)
				(justify left bottom)
				(hide yes)
			)
		)
		(property "MPN" "CC0201KRX6S5BB104"
			(at 123.19 153.67 0)
			(effects
				(font
					(size 1.27 1.27)
					(thickness 0.15)
				)
				(justify left bottom)
				(hide yes)
			)
		)
		(property "Val" "100n"
			(at 141.605 139.065 90)
			(effects
				(font
					(size 1.27 1.27)
					(thickness 0.15)
				)
				(justify left bottom)
			)
		)
		(property "License" "Apache-2.0"
			(at 118.11 153.67 0)
			(effects
				(font
					(size 1.27 1.27)
					(thickness 0.15)
				)
				(justify left bottom)
				(hide yes)
			)
		)
		(property "Author" "Antmicro"
			(at 115.57 153.67 0)
			(effects
				(font
					(size 1.27 1.27)
					(thickness 0.15)
				)
				(justify left bottom)
				(hide yes)
			)
		)
		(property "Voltage" ""
			(at 113.03 153.67 0)
			(effects
				(font
					(size 1.27 1.27)
				)
				(justify left bottom)
				(hide yes)
			)
		)
		(property "Dielectric" ""
			(at 110.49 153.67 0)
			(effects
				(font
					(size 1.27 1.27)
				)
				(justify left bottom)
				(hide yes)
			)
		)
		(pin "1"
		)
		(pin "2"
		)
		(instances
			(project "lpddr4-test-board"
				(path ""
					(reference "C71")
					(unit 1)
				)
			)
		)
	)
	(symbol
		(lib_id "antmicroCapacitorsmisc:C_100n_0201")
		(at 147.955 133.35 270)
		(unit 1)
		(exclude_from_sim no)
		(in_bom yes)
		(on_board yes)
		(dnp no)
		(property "Reference" "C75"
			(at 148.59 135.255 90)
			(effects
				(font
					(size 1.27 1.27)
					(thickness 0.15)
				)
				(justify left bottom)
			)
		)
		(property "Value" "C_100n_0201"
			(at 137.795 153.67 0)
			(effects
				(font
					(size 1.27 1.27)
					(thickness 0.15)
				)
				(justify left bottom)
				(hide yes)
			)
		)
		(property "Footprint" "antmicro-footprints:C_0201"
			(at 135.255 153.67 0)
			(effects
				(font
					(size 1.27 1.27)
					(thickness 0.15)
				)
				(justify left bottom)
				(hide yes)
			)
		)
		(property "Datasheet" " "
			(at 132.715 153.67 0)
			(effects
				(font
					(size 1.27 1.27)
					(thickness 0.15)
				)
				(justify left bottom)
				(hide yes)
			)
		)
		(property "Description" ""
			(at 147.955 133.35 0)
			(effects
				(font
					(size 1.27 1.27)
				)
			)
		)
		(property "Manufacturer" "Yaego"
			(at 127.635 153.67 0)
			(effects
				(font
					(size 1.27 1.27)
					(thickness 0.15)
				)
				(justify left bottom)
				(hide yes)
			)
		)
		(property "MPN" "CC0201KRX6S5BB104"
			(at 130.175 153.67 0)
			(effects
				(font
					(size 1.27 1.27)
					(thickness 0.15)
				)
				(justify left bottom)
				(hide yes)
			)
		)
		(property "Val" "100n"
			(at 148.59 139.065 90)
			(effects
				(font
					(size 1.27 1.27)
					(thickness 0.15)
				)
				(justify left bottom)
			)
		)
		(property "License" "Apache-2.0"
			(at 125.095 153.67 0)
			(effects
				(font
					(size 1.27 1.27)
					(thickness 0.15)
				)
				(justify left bottom)
				(hide yes)
			)
		)
		(property "Author" "Antmicro"
			(at 122.555 153.67 0)
			(effects
				(font
					(size 1.27 1.27)
					(thickness 0.15)
				)
				(justify left bottom)
				(hide yes)
			)
		)
		(property "Voltage" ""
			(at 120.015 153.67 0)
			(effects
				(font
					(size 1.27 1.27)
				)
				(justify left bottom)
				(hide yes)
			)
		)
		(property "Dielectric" ""
			(at 117.475 153.67 0)
			(effects
				(font
					(size 1.27 1.27)
				)
				(justify left bottom)
				(hide yes)
			)
		)
		(pin "1"
		)
		(pin "2"
		)
		(instances
			(project "lpddr4-test-board"
				(path ""
					(reference "C75")
					(unit 1)
				)
			)
		)
	)
	(symbol
		(lib_id "antmicroCapacitorsmisc:C_100n_0201")
		(at 196.85 95.25 270)
		(unit 1)
		(exclude_from_sim no)
		(in_bom yes)
		(on_board yes)
		(dnp no)
		(property "Reference" "C88"
			(at 197.485 97.155 90)
			(effects
				(font
					(size 1.27 1.27)
					(thickness 0.15)
				)
				(justify left bottom)
			)
		)
		(property "Value" "C_100n_0201"
			(at 186.69 115.57 0)
			(effects
				(font
					(size 1.27 1.27)
					(thickness 0.15)
				)
				(justify left bottom)
				(hide yes)
			)
		)
		(property "Footprint" "antmicro-footprints:C_0201"
			(at 184.15 115.57 0)
			(effects
				(font
					(size 1.27 1.27)
					(thickness 0.15)
				)
				(justify left bottom)
				(hide yes)
			)
		)
		(property "Datasheet" " "
			(at 181.61 115.57 0)
			(effects
				(font
					(size 1.27 1.27)
					(thickness 0.15)
				)
				(justify left bottom)
				(hide yes)
			)
		)
		(property "Description" ""
			(at 196.85 95.25 0)
			(effects
				(font
					(size 1.27 1.27)
				)
			)
		)
		(property "Manufacturer" "Yaego"
			(at 176.53 115.57 0)
			(effects
				(font
					(size 1.27 1.27)
					(thickness 0.15)
				)
				(justify left bottom)
				(hide yes)
			)
		)
		(property "MPN" "CC0201KRX6S5BB104"
			(at 179.07 115.57 0)
			(effects
				(font
					(size 1.27 1.27)
					(thickness 0.15)
				)
				(justify left bottom)
				(hide yes)
			)
		)
		(property "Val" "100n"
			(at 197.485 100.965 90)
			(effects
				(font
					(size 1.27 1.27)
					(thickness 0.15)
				)
				(justify left bottom)
			)
		)
		(property "License" "Apache-2.0"
			(at 173.99 115.57 0)
			(effects
				(font
					(size 1.27 1.27)
					(thickness 0.15)
				)
				(justify left bottom)
				(hide yes)
			)
		)
		(property "Author" "Antmicro"
			(at 171.45 115.57 0)
			(effects
				(font
					(size 1.27 1.27)
					(thickness 0.15)
				)
				(justify left bottom)
				(hide yes)
			)
		)
		(property "Voltage" ""
			(at 168.91 115.57 0)
			(effects
				(font
					(size 1.27 1.27)
				)
				(justify left bottom)
				(hide yes)
			)
		)
		(property "Dielectric" ""
			(at 166.37 115.57 0)
			(effects
				(font
					(size 1.27 1.27)
				)
				(justify left bottom)
				(hide yes)
			)
		)
		(pin "1"
		)
		(pin "2"
		)
		(instances
			(project "lpddr4-test-board"
				(path ""
					(reference "C88")
					(unit 1)
				)
			)
		)
	)
	(symbol
		(lib_id "antmicropower:GND")
		(at 113.03 101.6 0)
		(unit 1)
		(exclude_from_sim no)
		(in_bom yes)
		(on_board yes)
		(dnp no)
		(property "Reference" "#PWR0122"
			(at 121.92 104.14 0)
			(effects
				(font
					(size 1.27 1.27)
					(thickness 0.15)
				)
				(justify left bottom)
				(hide yes)
			)
		)
		(property "Value" "GND"
			(at 111.125 106.045 0)
			(effects
				(font
					(size 1.27 1.27)
					(thickness 0.15)
				)
				(justify left bottom)
			)
		)
		(property "Footprint" ""
			(at 121.92 109.22 0)
			(effects
				(font
					(size 1.27 1.27)
					(thickness 0.15)
				)
				(justify left bottom)
				(hide yes)
			)
		)
		(property "Datasheet" ""
			(at 121.92 114.3 0)
			(effects
				(font
					(size 1.27 1.27)
					(thickness 0.15)
				)
				(justify left bottom)
				(hide yes)
			)
		)
		(property "Description" ""
			(at 113.03 101.6 0)
			(effects
				(font
					(size 1.27 1.27)
				)
			)
		)
		(property "Author" "Antmicro"
			(at 121.92 109.22 0)
			(effects
				(font
					(size 1.27 1.27)
					(thickness 0.15)
				)
				(justify left bottom)
				(hide yes)
			)
		)
		(property "License" "Apache-2.0"
			(at 121.92 111.76 0)
			(effects
				(font
					(size 1.27 1.27)
					(thickness 0.15)
				)
				(justify left bottom)
				(hide yes)
			)
		)
		(pin "1"
		)
		(instances
			(project "lpddr4-test-board"
				(path ""
					(reference "#PWR0122")
					(unit 1)
				)
			)
		)
	)
	(symbol
		(lib_id "antmicroCapacitorsmisc:C_100n_0201")
		(at 203.835 95.25 270)
		(unit 1)
		(exclude_from_sim no)
		(in_bom yes)
		(on_board yes)
		(dnp no)
		(property "Reference" "C90"
			(at 204.47 97.155 90)
			(effects
				(font
					(size 1.27 1.27)
					(thickness 0.15)
				)
				(justify left bottom)
			)
		)
		(property "Value" "C_100n_0201"
			(at 193.675 115.57 0)
			(effects
				(font
					(size 1.27 1.27)
					(thickness 0.15)
				)
				(justify left bottom)
				(hide yes)
			)
		)
		(property "Footprint" "antmicro-footprints:C_0201"
			(at 191.135 115.57 0)
			(effects
				(font
					(size 1.27 1.27)
					(thickness 0.15)
				)
				(justify left bottom)
				(hide yes)
			)
		)
		(property "Datasheet" " "
			(at 188.595 115.57 0)
			(effects
				(font
					(size 1.27 1.27)
					(thickness 0.15)
				)
				(justify left bottom)
				(hide yes)
			)
		)
		(property "Description" ""
			(at 203.835 95.25 0)
			(effects
				(font
					(size 1.27 1.27)
				)
			)
		)
		(property "Manufacturer" "Yaego"
			(at 183.515 115.57 0)
			(effects
				(font
					(size 1.27 1.27)
					(thickness 0.15)
				)
				(justify left bottom)
				(hide yes)
			)
		)
		(property "MPN" "CC0201KRX6S5BB104"
			(at 186.055 115.57 0)
			(effects
				(font
					(size 1.27 1.27)
					(thickness 0.15)
				)
				(justify left bottom)
				(hide yes)
			)
		)
		(property "Val" "100n"
			(at 204.47 100.965 90)
			(effects
				(font
					(size 1.27 1.27)
					(thickness 0.15)
				)
				(justify left bottom)
			)
		)
		(property "License" "Apache-2.0"
			(at 180.975 115.57 0)
			(effects
				(font
					(size 1.27 1.27)
					(thickness 0.15)
				)
				(justify left bottom)
				(hide yes)
			)
		)
		(property "Author" "Antmicro"
			(at 178.435 115.57 0)
			(effects
				(font
					(size 1.27 1.27)
					(thickness 0.15)
				)
				(justify left bottom)
				(hide yes)
			)
		)
		(property "Voltage" ""
			(at 175.895 115.57 0)
			(effects
				(font
					(size 1.27 1.27)
				)
				(justify left bottom)
				(hide yes)
			)
		)
		(property "Dielectric" ""
			(at 173.355 115.57 0)
			(effects
				(font
					(size 1.27 1.27)
				)
				(justify left bottom)
				(hide yes)
			)
		)
		(pin "1"
		)
		(pin "2"
		)
		(instances
			(project "lpddr4-test-board"
				(path ""
					(reference "C90")
					(unit 1)
				)
			)
		)
	)
	(symbol
		(lib_id "antmicropower:GND")
		(at 106.045 101.6 0)
		(unit 1)
		(exclude_from_sim no)
		(in_bom yes)
		(on_board yes)
		(dnp no)
		(property "Reference" "#PWR0124"
			(at 114.935 104.14 0)
			(effects
				(font
					(size 1.27 1.27)
					(thickness 0.15)
				)
				(justify left bottom)
				(hide yes)
			)
		)
		(property "Value" "GND"
			(at 104.14 106.045 0)
			(effects
				(font
					(size 1.27 1.27)
					(thickness 0.15)
				)
				(justify left bottom)
			)
		)
		(property "Footprint" ""
			(at 114.935 109.22 0)
			(effects
				(font
					(size 1.27 1.27)
					(thickness 0.15)
				)
				(justify left bottom)
				(hide yes)
			)
		)
		(property "Datasheet" ""
			(at 114.935 114.3 0)
			(effects
				(font
					(size 1.27 1.27)
					(thickness 0.15)
				)
				(justify left bottom)
				(hide yes)
			)
		)
		(property "Description" ""
			(at 106.045 101.6 0)
			(effects
				(font
					(size 1.27 1.27)
				)
			)
		)
		(property "Author" "Antmicro"
			(at 114.935 109.22 0)
			(effects
				(font
					(size 1.27 1.27)
					(thickness 0.15)
				)
				(justify left bottom)
				(hide yes)
			)
		)
		(property "License" "Apache-2.0"
			(at 114.935 111.76 0)
			(effects
				(font
					(size 1.27 1.27)
					(thickness 0.15)
				)
				(justify left bottom)
				(hide yes)
			)
		)
		(pin "1"
		)
		(instances
			(project "lpddr4-test-board"
				(path ""
					(reference "#PWR0124")
					(unit 1)
				)
			)
		)
	)
	(symbol
		(lib_id "antmicroCapacitorsmisc:C_100n_0201")
		(at 210.82 95.25 270)
		(unit 1)
		(exclude_from_sim no)
		(in_bom yes)
		(on_board yes)
		(dnp no)
		(property "Reference" "C92"
			(at 211.455 97.155 90)
			(effects
				(font
					(size 1.27 1.27)
					(thickness 0.15)
				)
				(justify left bottom)
			)
		)
		(property "Value" "C_100n_0201"
			(at 200.66 115.57 0)
			(effects
				(font
					(size 1.27 1.27)
					(thickness 0.15)
				)
				(justify left bottom)
				(hide yes)
			)
		)
		(property "Footprint" "antmicro-footprints:C_0201"
			(at 198.12 115.57 0)
			(effects
				(font
					(size 1.27 1.27)
					(thickness 0.15)
				)
				(justify left bottom)
				(hide yes)
			)
		)
		(property "Datasheet" " "
			(at 195.58 115.57 0)
			(effects
				(font
					(size 1.27 1.27)
					(thickness 0.15)
				)
				(justify left bottom)
				(hide yes)
			)
		)
		(property "Description" ""
			(at 210.82 95.25 0)
			(effects
				(font
					(size 1.27 1.27)
				)
			)
		)
		(property "Manufacturer" "Yaego"
			(at 190.5 115.57 0)
			(effects
				(font
					(size 1.27 1.27)
					(thickness 0.15)
				)
				(justify left bottom)
				(hide yes)
			)
		)
		(property "MPN" "CC0201KRX6S5BB104"
			(at 193.04 115.57 0)
			(effects
				(font
					(size 1.27 1.27)
					(thickness 0.15)
				)
				(justify left bottom)
				(hide yes)
			)
		)
		(property "Val" "100n"
			(at 211.455 100.965 90)
			(effects
				(font
					(size 1.27 1.27)
					(thickness 0.15)
				)
				(justify left bottom)
			)
		)
		(property "License" "Apache-2.0"
			(at 187.96 115.57 0)
			(effects
				(font
					(size 1.27 1.27)
					(thickness 0.15)
				)
				(justify left bottom)
				(hide yes)
			)
		)
		(property "Author" "Antmicro"
			(at 185.42 115.57 0)
			(effects
				(font
					(size 1.27 1.27)
					(thickness 0.15)
				)
				(justify left bottom)
				(hide yes)
			)
		)
		(property "Voltage" ""
			(at 182.88 115.57 0)
			(effects
				(font
					(size 1.27 1.27)
				)
				(justify left bottom)
				(hide yes)
			)
		)
		(property "Dielectric" ""
			(at 180.34 115.57 0)
			(effects
				(font
					(size 1.27 1.27)
				)
				(justify left bottom)
				(hide yes)
			)
		)
		(pin "1"
		)
		(pin "2"
		)
		(instances
			(project "lpddr4-test-board"
				(path ""
					(reference "C92")
					(unit 1)
				)
			)
		)
	)
	(symbol
		(lib_id "antmicropower:GND")
		(at 99.06 101.6 0)
		(unit 1)
		(exclude_from_sim no)
		(in_bom yes)
		(on_board yes)
		(dnp no)
		(property "Reference" "#PWR0126"
			(at 107.95 104.14 0)
			(effects
				(font
					(size 1.27 1.27)
					(thickness 0.15)
				)
				(justify left bottom)
				(hide yes)
			)
		)
		(property "Value" "GND"
			(at 97.155 106.045 0)
			(effects
				(font
					(size 1.27 1.27)
					(thickness 0.15)
				)
				(justify left bottom)
			)
		)
		(property "Footprint" ""
			(at 107.95 109.22 0)
			(effects
				(font
					(size 1.27 1.27)
					(thickness 0.15)
				)
				(justify left bottom)
				(hide yes)
			)
		)
		(property "Datasheet" ""
			(at 107.95 114.3 0)
			(effects
				(font
					(size 1.27 1.27)
					(thickness 0.15)
				)
				(justify left bottom)
				(hide yes)
			)
		)
		(property "Description" ""
			(at 99.06 101.6 0)
			(effects
				(font
					(size 1.27 1.27)
				)
			)
		)
		(property "Author" "Antmicro"
			(at 107.95 109.22 0)
			(effects
				(font
					(size 1.27 1.27)
					(thickness 0.15)
				)
				(justify left bottom)
				(hide yes)
			)
		)
		(property "License" "Apache-2.0"
			(at 107.95 111.76 0)
			(effects
				(font
					(size 1.27 1.27)
					(thickness 0.15)
				)
				(justify left bottom)
				(hide yes)
			)
		)
		(pin "1"
		)
		(instances
			(project "lpddr4-test-board"
				(path ""
					(reference "#PWR0126")
					(unit 1)
				)
			)
		)
	)
	(symbol
		(lib_id "antmicropower:GND")
		(at 99.06 82.55 0)
		(unit 1)
		(exclude_from_sim no)
		(in_bom yes)
		(on_board yes)
		(dnp no)
		(property "Reference" "#PWR0117"
			(at 107.95 85.09 0)
			(effects
				(font
					(size 1.27 1.27)
					(thickness 0.15)
				)
				(justify left bottom)
				(hide yes)
			)
		)
		(property "Value" "GND"
			(at 97.155 86.995 0)
			(effects
				(font
					(size 1.27 1.27)
					(thickness 0.15)
				)
				(justify left bottom)
			)
		)
		(property "Footprint" ""
			(at 107.95 90.17 0)
			(effects
				(font
					(size 1.27 1.27)
					(thickness 0.15)
				)
				(justify left bottom)
				(hide yes)
			)
		)
		(property "Datasheet" ""
			(at 107.95 95.25 0)
			(effects
				(font
					(size 1.27 1.27)
					(thickness 0.15)
				)
				(justify left bottom)
				(hide yes)
			)
		)
		(property "Description" ""
			(at 99.06 82.55 0)
			(effects
				(font
					(size 1.27 1.27)
				)
			)
		)
		(property "Author" "Antmicro"
			(at 107.95 90.17 0)
			(effects
				(font
					(size 1.27 1.27)
					(thickness 0.15)
				)
				(justify left bottom)
				(hide yes)
			)
		)
		(property "License" "Apache-2.0"
			(at 107.95 92.71 0)
			(effects
				(font
					(size 1.27 1.27)
					(thickness 0.15)
				)
				(justify left bottom)
				(hide yes)
			)
		)
		(pin "1"
		)
		(instances
			(project "lpddr4-test-board"
				(path ""
					(reference "#PWR0117")
					(unit 1)
				)
			)
		)
	)
	(symbol
		(lib_id "antmicropower:GND")
		(at 92.71 82.55 0)
		(unit 1)
		(exclude_from_sim no)
		(in_bom yes)
		(on_board yes)
		(dnp no)
		(property "Reference" "#PWR0118"
			(at 101.6 85.09 0)
			(effects
				(font
					(size 1.27 1.27)
					(thickness 0.15)
				)
				(justify left bottom)
				(hide yes)
			)
		)
		(property "Value" "GND"
			(at 90.805 86.995 0)
			(effects
				(font
					(size 1.27 1.27)
					(thickness 0.15)
				)
				(justify left bottom)
			)
		)
		(property "Footprint" ""
			(at 101.6 90.17 0)
			(effects
				(font
					(size 1.27 1.27)
					(thickness 0.15)
				)
				(justify left bottom)
				(hide yes)
			)
		)
		(property "Datasheet" ""
			(at 101.6 95.25 0)
			(effects
				(font
					(size 1.27 1.27)
					(thickness 0.15)
				)
				(justify left bottom)
				(hide yes)
			)
		)
		(property "Description" ""
			(at 92.71 82.55 0)
			(effects
				(font
					(size 1.27 1.27)
				)
			)
		)
		(property "Author" "Antmicro"
			(at 101.6 90.17 0)
			(effects
				(font
					(size 1.27 1.27)
					(thickness 0.15)
				)
				(justify left bottom)
				(hide yes)
			)
		)
		(property "License" "Apache-2.0"
			(at 101.6 92.71 0)
			(effects
				(font
					(size 1.27 1.27)
					(thickness 0.15)
				)
				(justify left bottom)
				(hide yes)
			)
		)
		(pin "1"
		)
		(instances
			(project "lpddr4-test-board"
				(path ""
					(reference "#PWR0118")
					(unit 1)
				)
			)
		)
	)
	(symbol
		(lib_id "antmicropower:GND")
		(at 92.075 63.5 0)
		(unit 1)
		(exclude_from_sim no)
		(in_bom yes)
		(on_board yes)
		(dnp no)
		(property "Reference" "#PWR0120"
			(at 100.965 66.04 0)
			(effects
				(font
					(size 1.27 1.27)
					(thickness 0.15)
				)
				(justify left bottom)
				(hide yes)
			)
		)
		(property "Value" "GND"
			(at 90.17 67.945 0)
			(effects
				(font
					(size 1.27 1.27)
					(thickness 0.15)
				)
				(justify left bottom)
			)
		)
		(property "Footprint" ""
			(at 100.965 71.12 0)
			(effects
				(font
					(size 1.27 1.27)
					(thickness 0.15)
				)
				(justify left bottom)
				(hide yes)
			)
		)
		(property "Datasheet" ""
			(at 100.965 76.2 0)
			(effects
				(font
					(size 1.27 1.27)
					(thickness 0.15)
				)
				(justify left bottom)
				(hide yes)
			)
		)
		(property "Description" ""
			(at 92.075 63.5 0)
			(effects
				(font
					(size 1.27 1.27)
				)
			)
		)
		(property "Author" "Antmicro"
			(at 100.965 71.12 0)
			(effects
				(font
					(size 1.27 1.27)
					(thickness 0.15)
				)
				(justify left bottom)
				(hide yes)
			)
		)
		(property "License" "Apache-2.0"
			(at 100.965 73.66 0)
			(effects
				(font
					(size 1.27 1.27)
					(thickness 0.15)
				)
				(justify left bottom)
				(hide yes)
			)
		)
		(pin "1"
		)
		(instances
			(project "lpddr4-test-board"
				(path ""
					(reference "#PWR0120")
					(unit 1)
				)
			)
		)
	)
	(symbol
		(lib_id "antmicroCapacitorsmisc:C_100n_0201")
		(at 161.925 171.45 270)
		(unit 1)
		(exclude_from_sim no)
		(in_bom yes)
		(on_board yes)
		(dnp no)
		(property "Reference" "C76"
			(at 162.56 173.355 90)
			(effects
				(font
					(size 1.27 1.27)
					(thickness 0.15)
				)
				(justify left bottom)
			)
		)
		(property "Value" "C_100n_0201"
			(at 151.765 191.77 0)
			(effects
				(font
					(size 1.27 1.27)
					(thickness 0.15)
				)
				(justify left bottom)
				(hide yes)
			)
		)
		(property "Footprint" "antmicro-footprints:C_0201"
			(at 149.225 191.77 0)
			(effects
				(font
					(size 1.27 1.27)
					(thickness 0.15)
				)
				(justify left bottom)
				(hide yes)
			)
		)
		(property "Datasheet" " "
			(at 146.685 191.77 0)
			(effects
				(font
					(size 1.27 1.27)
					(thickness 0.15)
				)
				(justify left bottom)
				(hide yes)
			)
		)
		(property "Description" ""
			(at 161.925 171.45 0)
			(effects
				(font
					(size 1.27 1.27)
				)
			)
		)
		(property "Manufacturer" "Yaego"
			(at 141.605 191.77 0)
			(effects
				(font
					(size 1.27 1.27)
					(thickness 0.15)
				)
				(justify left bottom)
				(hide yes)
			)
		)
		(property "MPN" "CC0201KRX6S5BB104"
			(at 144.145 191.77 0)
			(effects
				(font
					(size 1.27 1.27)
					(thickness 0.15)
				)
				(justify left bottom)
				(hide yes)
			)
		)
		(property "Val" "100n"
			(at 162.56 177.165 90)
			(effects
				(font
					(size 1.27 1.27)
					(thickness 0.15)
				)
				(justify left bottom)
			)
		)
		(property "License" "Apache-2.0"
			(at 139.065 191.77 0)
			(effects
				(font
					(size 1.27 1.27)
					(thickness 0.15)
				)
				(justify left bottom)
				(hide yes)
			)
		)
		(property "Author" "Antmicro"
			(at 136.525 191.77 0)
			(effects
				(font
					(size 1.27 1.27)
					(thickness 0.15)
				)
				(justify left bottom)
				(hide yes)
			)
		)
		(property "Voltage" ""
			(at 133.985 191.77 0)
			(effects
				(font
					(size 1.27 1.27)
				)
				(justify left bottom)
				(hide yes)
			)
		)
		(property "Dielectric" ""
			(at 131.445 191.77 0)
			(effects
				(font
					(size 1.27 1.27)
				)
				(justify left bottom)
				(hide yes)
			)
		)
		(pin "1"
		)
		(pin "2"
		)
		(instances
			(project "lpddr4-test-board"
				(path ""
					(reference "C76")
					(unit 1)
				)
			)
		)
	)
	(symbol
		(lib_id "antmicroCapacitorsmisc:C_100n_0201")
		(at 168.91 171.45 270)
		(unit 1)
		(exclude_from_sim no)
		(in_bom yes)
		(on_board yes)
		(dnp no)
		(property "Reference" "C80"
			(at 169.545 173.355 90)
			(effects
				(font
					(size 1.27 1.27)
					(thickness 0.15)
				)
				(justify left bottom)
			)
		)
		(property "Value" "C_100n_0201"
			(at 158.75 191.77 0)
			(effects
				(font
					(size 1.27 1.27)
					(thickness 0.15)
				)
				(justify left bottom)
				(hide yes)
			)
		)
		(property "Footprint" "antmicro-footprints:C_0201"
			(at 156.21 191.77 0)
			(effects
				(font
					(size 1.27 1.27)
					(thickness 0.15)
				)
				(justify left bottom)
				(hide yes)
			)
		)
		(property "Datasheet" " "
			(at 153.67 191.77 0)
			(effects
				(font
					(size 1.27 1.27)
					(thickness 0.15)
				)
				(justify left bottom)
				(hide yes)
			)
		)
		(property "Description" ""
			(at 168.91 171.45 0)
			(effects
				(font
					(size 1.27 1.27)
				)
			)
		)
		(property "Manufacturer" "Yaego"
			(at 148.59 191.77 0)
			(effects
				(font
					(size 1.27 1.27)
					(thickness 0.15)
				)
				(justify left bottom)
				(hide yes)
			)
		)
		(property "MPN" "CC0201KRX6S5BB104"
			(at 151.13 191.77 0)
			(effects
				(font
					(size 1.27 1.27)
					(thickness 0.15)
				)
				(justify left bottom)
				(hide yes)
			)
		)
		(property "Val" "100n"
			(at 169.545 177.165 90)
			(effects
				(font
					(size 1.27 1.27)
					(thickness 0.15)
				)
				(justify left bottom)
			)
		)
		(property "License" "Apache-2.0"
			(at 146.05 191.77 0)
			(effects
				(font
					(size 1.27 1.27)
					(thickness 0.15)
				)
				(justify left bottom)
				(hide yes)
			)
		)
		(property "Author" "Antmicro"
			(at 143.51 191.77 0)
			(effects
				(font
					(size 1.27 1.27)
					(thickness 0.15)
				)
				(justify left bottom)
				(hide yes)
			)
		)
		(property "Voltage" ""
			(at 140.97 191.77 0)
			(effects
				(font
					(size 1.27 1.27)
				)
				(justify left bottom)
				(hide yes)
			)
		)
		(property "Dielectric" ""
			(at 138.43 191.77 0)
			(effects
				(font
					(size 1.27 1.27)
				)
				(justify left bottom)
				(hide yes)
			)
		)
		(pin "1"
		)
		(pin "2"
		)
		(instances
			(project "lpddr4-test-board"
				(path ""
					(reference "C80")
					(unit 1)
				)
			)
		)
	)
	(symbol
		(lib_id "antmicroCapacitors0603:C_47u_0603")
		(at 92.075 114.3 270)
		(unit 1)
		(exclude_from_sim no)
		(in_bom yes)
		(on_board yes)
		(dnp no)
		(property "Reference" "C38"
			(at 92.71 116.205 90)
			(effects
				(font
					(size 1.27 1.27)
					(thickness 0.15)
				)
				(justify left bottom)
			)
		)
		(property "Value" "C_47u_0603"
			(at 81.915 134.62 0)
			(effects
				(font
					(size 1.27 1.27)
					(thickness 0.15)
				)
				(justify left bottom)
				(hide yes)
			)
		)
		(property "Footprint" "antmicro-footprints:C_0603_1608Metric"
			(at 79.375 134.62 0)
			(effects
				(font
					(size 1.27 1.27)
					(thickness 0.15)
				)
				(justify left bottom)
				(hide yes)
			)
		)
		(property "Datasheet" " "
			(at 76.835 134.62 0)
			(effects
				(font
					(size 1.27 1.27)
					(thickness 0.15)
				)
				(justify left bottom)
				(hide yes)
			)
		)
		(property "Description" ""
			(at 92.075 114.3 0)
			(effects
				(font
					(size 1.27 1.27)
				)
			)
		)
		(property "Manufacturer" "Murata"
			(at 71.755 134.62 0)
			(effects
				(font
					(size 1.27 1.27)
					(thickness 0.15)
				)
				(justify left bottom)
				(hide yes)
			)
		)
		(property "MPN" "GRM188R60J476ME15D"
			(at 74.295 134.62 0)
			(effects
				(font
					(size 1.27 1.27)
					(thickness 0.15)
				)
				(justify left bottom)
				(hide yes)
			)
		)
		(property "Val" "47u"
			(at 92.71 120.015 90)
			(effects
				(font
					(size 1.27 1.27)
					(thickness 0.15)
				)
				(justify left bottom)
			)
		)
		(property "License" "Apache-2.0"
			(at 69.215 134.62 0)
			(effects
				(font
					(size 1.27 1.27)
					(thickness 0.15)
				)
				(justify left bottom)
				(hide yes)
			)
		)
		(property "Author" "Antmicro"
			(at 66.675 134.62 0)
			(effects
				(font
					(size 1.27 1.27)
					(thickness 0.15)
				)
				(justify left bottom)
				(hide yes)
			)
		)
		(property "Voltage" ""
			(at 64.135 134.62 0)
			(effects
				(font
					(size 1.27 1.27)
				)
				(justify left bottom)
				(hide yes)
			)
		)
		(property "Dielectric" ""
			(at 61.595 134.62 0)
			(effects
				(font
					(size 1.27 1.27)
				)
				(justify left bottom)
				(hide yes)
			)
		)
		(pin "1"
		)
		(pin "2"
		)
		(instances
			(project "lpddr4-test-board"
				(path ""
					(reference "C38")
					(unit 1)
				)
			)
		)
	)
	(symbol
		(lib_id "antmicroCapacitors0603:C_47u_0603")
		(at 99.06 114.3 270)
		(unit 1)
		(exclude_from_sim no)
		(in_bom yes)
		(on_board yes)
		(dnp no)
		(property "Reference" "C42"
			(at 99.695 116.205 90)
			(effects
				(font
					(size 1.27 1.27)
					(thickness 0.15)
				)
				(justify left bottom)
			)
		)
		(property "Value" "C_47u_0603"
			(at 88.9 134.62 0)
			(effects
				(font
					(size 1.27 1.27)
					(thickness 0.15)
				)
				(justify left bottom)
				(hide yes)
			)
		)
		(property "Footprint" "antmicro-footprints:C_0603_1608Metric"
			(at 86.36 134.62 0)
			(effects
				(font
					(size 1.27 1.27)
					(thickness 0.15)
				)
				(justify left bottom)
				(hide yes)
			)
		)
		(property "Datasheet" " "
			(at 83.82 134.62 0)
			(effects
				(font
					(size 1.27 1.27)
					(thickness 0.15)
				)
				(justify left bottom)
				(hide yes)
			)
		)
		(property "Description" ""
			(at 99.06 114.3 0)
			(effects
				(font
					(size 1.27 1.27)
				)
			)
		)
		(property "Manufacturer" "Murata"
			(at 78.74 134.62 0)
			(effects
				(font
					(size 1.27 1.27)
					(thickness 0.15)
				)
				(justify left bottom)
				(hide yes)
			)
		)
		(property "MPN" "GRM188R60J476ME15D"
			(at 81.28 134.62 0)
			(effects
				(font
					(size 1.27 1.27)
					(thickness 0.15)
				)
				(justify left bottom)
				(hide yes)
			)
		)
		(property "Val" "47u"
			(at 99.695 120.015 90)
			(effects
				(font
					(size 1.27 1.27)
					(thickness 0.15)
				)
				(justify left bottom)
			)
		)
		(property "License" "Apache-2.0"
			(at 76.2 134.62 0)
			(effects
				(font
					(size 1.27 1.27)
					(thickness 0.15)
				)
				(justify left bottom)
				(hide yes)
			)
		)
		(property "Author" "Antmicro"
			(at 73.66 134.62 0)
			(effects
				(font
					(size 1.27 1.27)
					(thickness 0.15)
				)
				(justify left bottom)
				(hide yes)
			)
		)
		(property "Voltage" ""
			(at 71.12 134.62 0)
			(effects
				(font
					(size 1.27 1.27)
				)
				(justify left bottom)
				(hide yes)
			)
		)
		(property "Dielectric" ""
			(at 68.58 134.62 0)
			(effects
				(font
					(size 1.27 1.27)
				)
				(justify left bottom)
				(hide yes)
			)
		)
		(pin "1"
		)
		(pin "2"
		)
		(instances
			(project "lpddr4-test-board"
				(path ""
					(reference "C42")
					(unit 1)
				)
			)
		)
	)
	(symbol
		(lib_id "antmicroCapacitors0402:C_4u7_0402")
		(at 120.015 114.3 270)
		(unit 1)
		(exclude_from_sim no)
		(in_bom yes)
		(on_board yes)
		(dnp no)
		(property "Reference" "C34"
			(at 120.65 116.205 90)
			(effects
				(font
					(size 1.27 1.27)
					(thickness 0.15)
				)
				(justify left bottom)
			)
		)
		(property "Value" "C_4u7_0402"
			(at 109.855 134.62 0)
			(effects
				(font
					(size 1.27 1.27)
					(thickness 0.15)
				)
				(justify left bottom)
				(hide yes)
			)
		)
		(property "Footprint" "antmicro-footprints:C_0402_1005Metric"
			(at 107.315 134.62 0)
			(effects
				(font
					(size 1.27 1.27)
					(thickness 0.15)
				)
				(justify left bottom)
				(hide yes)
			)
		)
		(property "Datasheet" " "
			(at 104.775 134.62 0)
			(effects
				(font
					(size 1.27 1.27)
					(thickness 0.15)
				)
				(justify left bottom)
				(hide yes)
			)
		)
		(property "Description" ""
			(at 120.015 114.3 0)
			(effects
				(font
					(size 1.27 1.27)
				)
			)
		)
		(property "Manufacturer" "Murata"
			(at 99.695 134.62 0)
			(effects
				(font
					(size 1.27 1.27)
					(thickness 0.15)
				)
				(justify left bottom)
				(hide yes)
			)
		)
		(property "MPN" "GRM155R61A475MEAAD"
			(at 102.235 134.62 0)
			(effects
				(font
					(size 1.27 1.27)
					(thickness 0.15)
				)
				(justify left bottom)
				(hide yes)
			)
		)
		(property "Val" "4u7"
			(at 120.65 120.015 90)
			(effects
				(font
					(size 1.27 1.27)
					(thickness 0.15)
				)
				(justify left bottom)
			)
		)
		(property "License" "Apache-2.0"
			(at 97.155 134.62 0)
			(effects
				(font
					(size 1.27 1.27)
					(thickness 0.15)
				)
				(justify left bottom)
				(hide yes)
			)
		)
		(property "Author" "Antmicro"
			(at 94.615 134.62 0)
			(effects
				(font
					(size 1.27 1.27)
					(thickness 0.15)
				)
				(justify left bottom)
				(hide yes)
			)
		)
		(property "Voltage" ""
			(at 92.075 134.62 0)
			(effects
				(font
					(size 1.27 1.27)
				)
				(justify left bottom)
				(hide yes)
			)
		)
		(property "Dielectric" ""
			(at 89.535 134.62 0)
			(effects
				(font
					(size 1.27 1.27)
				)
				(justify left bottom)
				(hide yes)
			)
		)
		(pin "1"
		)
		(pin "2"
		)
		(instances
			(project "lpddr4-test-board"
				(path ""
					(reference "C34")
					(unit 1)
				)
			)
		)
	)
	(symbol
		(lib_id "antmicroCapacitors0402:C_4u7_0402")
		(at 113.03 114.3 270)
		(unit 1)
		(exclude_from_sim no)
		(in_bom yes)
		(on_board yes)
		(dnp no)
		(property "Reference" "C30"
			(at 113.665 116.205 90)
			(effects
				(font
					(size 1.27 1.27)
					(thickness 0.15)
				)
				(justify left bottom)
			)
		)
		(property "Value" "C_4u7_0402"
			(at 102.87 134.62 0)
			(effects
				(font
					(size 1.27 1.27)
					(thickness 0.15)
				)
				(justify left bottom)
				(hide yes)
			)
		)
		(property "Footprint" "antmicro-footprints:C_0402_1005Metric"
			(at 100.33 134.62 0)
			(effects
				(font
					(size 1.27 1.27)
					(thickness 0.15)
				)
				(justify left bottom)
				(hide yes)
			)
		)
		(property "Datasheet" " "
			(at 97.79 134.62 0)
			(effects
				(font
					(size 1.27 1.27)
					(thickness 0.15)
				)
				(justify left bottom)
				(hide yes)
			)
		)
		(property "Description" ""
			(at 113.03 114.3 0)
			(effects
				(font
					(size 1.27 1.27)
				)
			)
		)
		(property "Manufacturer" "Murata"
			(at 92.71 134.62 0)
			(effects
				(font
					(size 1.27 1.27)
					(thickness 0.15)
				)
				(justify left bottom)
				(hide yes)
			)
		)
		(property "MPN" "GRM155R61A475MEAAD"
			(at 95.25 134.62 0)
			(effects
				(font
					(size 1.27 1.27)
					(thickness 0.15)
				)
				(justify left bottom)
				(hide yes)
			)
		)
		(property "Val" "4u7"
			(at 113.665 120.015 90)
			(effects
				(font
					(size 1.27 1.27)
					(thickness 0.15)
				)
				(justify left bottom)
			)
		)
		(property "License" "Apache-2.0"
			(at 90.17 134.62 0)
			(effects
				(font
					(size 1.27 1.27)
					(thickness 0.15)
				)
				(justify left bottom)
				(hide yes)
			)
		)
		(property "Author" "Antmicro"
			(at 87.63 134.62 0)
			(effects
				(font
					(size 1.27 1.27)
					(thickness 0.15)
				)
				(justify left bottom)
				(hide yes)
			)
		)
		(property "Voltage" ""
			(at 85.09 134.62 0)
			(effects
				(font
					(size 1.27 1.27)
				)
				(justify left bottom)
				(hide yes)
			)
		)
		(property "Dielectric" ""
			(at 82.55 134.62 0)
			(effects
				(font
					(size 1.27 1.27)
				)
				(justify left bottom)
				(hide yes)
			)
		)
		(pin "1"
		)
		(pin "2"
		)
		(instances
			(project "lpddr4-test-board"
				(path ""
					(reference "C30")
					(unit 1)
				)
			)
		)
	)
	(symbol
		(lib_id "antmicroCapacitors0402:C_4u7_0402")
		(at 106.045 114.3 270)
		(unit 1)
		(exclude_from_sim no)
		(in_bom yes)
		(on_board yes)
		(dnp no)
		(property "Reference" "C26"
			(at 106.68 116.205 90)
			(effects
				(font
					(size 1.27 1.27)
					(thickness 0.15)
				)
				(justify left bottom)
			)
		)
		(property "Value" "C_4u7_0402"
			(at 95.885 134.62 0)
			(effects
				(font
					(size 1.27 1.27)
					(thickness 0.15)
				)
				(justify left bottom)
				(hide yes)
			)
		)
		(property "Footprint" "antmicro-footprints:C_0402_1005Metric"
			(at 93.345 134.62 0)
			(effects
				(font
					(size 1.27 1.27)
					(thickness 0.15)
				)
				(justify left bottom)
				(hide yes)
			)
		)
		(property "Datasheet" " "
			(at 90.805 134.62 0)
			(effects
				(font
					(size 1.27 1.27)
					(thickness 0.15)
				)
				(justify left bottom)
				(hide yes)
			)
		)
		(property "Description" ""
			(at 106.045 114.3 0)
			(effects
				(font
					(size 1.27 1.27)
				)
			)
		)
		(property "Manufacturer" "Murata"
			(at 85.725 134.62 0)
			(effects
				(font
					(size 1.27 1.27)
					(thickness 0.15)
				)
				(justify left bottom)
				(hide yes)
			)
		)
		(property "MPN" "GRM155R61A475MEAAD"
			(at 88.265 134.62 0)
			(effects
				(font
					(size 1.27 1.27)
					(thickness 0.15)
				)
				(justify left bottom)
				(hide yes)
			)
		)
		(property "Val" "4u7"
			(at 106.68 120.015 90)
			(effects
				(font
					(size 1.27 1.27)
					(thickness 0.15)
				)
				(justify left bottom)
			)
		)
		(property "License" "Apache-2.0"
			(at 83.185 134.62 0)
			(effects
				(font
					(size 1.27 1.27)
					(thickness 0.15)
				)
				(justify left bottom)
				(hide yes)
			)
		)
		(property "Author" "Antmicro"
			(at 80.645 134.62 0)
			(effects
				(font
					(size 1.27 1.27)
					(thickness 0.15)
				)
				(justify left bottom)
				(hide yes)
			)
		)
		(property "Voltage" ""
			(at 78.105 134.62 0)
			(effects
				(font
					(size 1.27 1.27)
				)
				(justify left bottom)
				(hide yes)
			)
		)
		(property "Dielectric" ""
			(at 75.565 134.62 0)
			(effects
				(font
					(size 1.27 1.27)
				)
				(justify left bottom)
				(hide yes)
			)
		)
		(pin "1"
		)
		(pin "2"
		)
		(instances
			(project "lpddr4-test-board"
				(path ""
					(reference "C26")
					(unit 1)
				)
			)
		)
	)
	(symbol
		(lib_id "antmicroCapacitorspol:C_Pol_100u_6V_KEMET-T490-A")
		(at 92.71 76.2 270)
		(unit 1)
		(exclude_from_sim no)
		(in_bom yes)
		(on_board yes)
		(dnp no)
		(property "Reference" "C86"
			(at 93.218 75.946 90)
			(effects
				(font
					(size 1.27 1.27)
					(thickness 0.15)
				)
				(justify left)
			)
		)
		(property "Value" "C_Pol_100u_6V_KEMET-T490-A"
			(at 87.63 90.17 0)
			(effects
				(font
					(size 1.27 1.27)
					(thickness 0.15)
				)
				(justify left bottom)
				(hide yes)
			)
		)
		(property "Footprint" "antmicro-footprints:C_Pol_EIA-A"
			(at 85.09 90.17 0)
			(effects
				(font
					(size 1.27 1.27)
					(thickness 0.15)
				)
				(justify left bottom)
				(hide yes)
			)
		)
		(property "Datasheet" "https://www.kemet.com/en/us/capacitors/product/T490A107M006ATE800.html"
			(at 82.55 90.17 0)
			(effects
				(font
					(size 1.27 1.27)
					(thickness 0.15)
				)
				(justify left bottom)
				(hide yes)
			)
		)
		(property "Description" "Surface Mount Tantalum Capacitor,  Solid SMD 6V 100uF 1206 20% ESR=800mOhms"
			(at 67.31 90.17 0)
			(effects
				(font
					(size 1.27 1.27)
				)
				(justify left bottom)
				(hide yes)
			)
		)
		(property "Manufacturer" "KEMET"
			(at 77.47 90.17 0)
			(effects
				(font
					(size 1.27 1.27)
					(thickness 0.15)
				)
				(justify left bottom)
				(hide yes)
			)
		)
		(property "MPN" "T490A107M006ATE800"
			(at 80.01 90.17 0)
			(effects
				(font
					(size 1.27 1.27)
					(thickness 0.15)
				)
				(justify left bottom)
				(hide yes)
			)
		)
		(property "Val" "100u"
			(at 93.218 81.026 90)
			(effects
				(font
					(size 1.27 1.27)
					(thickness 0.15)
				)
				(justify left)
			)
		)
		(property "License" "Apache-2.0"
			(at 74.93 90.17 0)
			(effects
				(font
					(size 1.27 1.27)
					(thickness 0.15)
				)
				(justify left bottom)
				(hide yes)
			)
		)
		(property "Author" "Antmicro"
			(at 72.39 90.17 0)
			(effects
				(font
					(size 1.27 1.27)
					(thickness 0.15)
				)
				(justify left bottom)
				(hide yes)
			)
		)
		(property "Voltage" "6V"
			(at 69.85 90.17 0)
			(effects
				(font
					(size 1.27 1.27)
				)
				(justify left bottom)
				(hide yes)
			)
		)
		(property "Dielectric" "template_dielectric"
			(at 67.31 90.17 0)
			(effects
				(font
					(size 1.27 1.27)
				)
				(justify left bottom)
				(hide yes)
			)
		)
		(pin "1"
		)
		(pin "2"
		)
		(instances
			(project "lpddr4-test-board"
				(path ""
					(reference "C86")
					(unit 1)
				)
			)
		)
	)
	(symbol
		(lib_id "antmicroCapacitors0402:C_4u7_0402")
		(at 106.045 76.2 270)
		(unit 1)
		(exclude_from_sim no)
		(in_bom yes)
		(on_board yes)
		(dnp no)
		(property "Reference" "C84"
			(at 106.68 78.105 90)
			(effects
				(font
					(size 1.27 1.27)
					(thickness 0.15)
				)
				(justify left bottom)
			)
		)
		(property "Value" "C_4u7_0402"
			(at 95.885 96.52 0)
			(effects
				(font
					(size 1.27 1.27)
					(thickness 0.15)
				)
				(justify left bottom)
				(hide yes)
			)
		)
		(property "Footprint" "antmicro-footprints:C_0402_1005Metric"
			(at 93.345 96.52 0)
			(effects
				(font
					(size 1.27 1.27)
					(thickness 0.15)
				)
				(justify left bottom)
				(hide yes)
			)
		)
		(property "Datasheet" " "
			(at 90.805 96.52 0)
			(effects
				(font
					(size 1.27 1.27)
					(thickness 0.15)
				)
				(justify left bottom)
				(hide yes)
			)
		)
		(property "Description" ""
			(at 106.045 76.2 0)
			(effects
				(font
					(size 1.27 1.27)
				)
			)
		)
		(property "Manufacturer" "Murata"
			(at 85.725 96.52 0)
			(effects
				(font
					(size 1.27 1.27)
					(thickness 0.15)
				)
				(justify left bottom)
				(hide yes)
			)
		)
		(property "MPN" "GRM155R61A475MEAAD"
			(at 88.265 96.52 0)
			(effects
				(font
					(size 1.27 1.27)
					(thickness 0.15)
				)
				(justify left bottom)
				(hide yes)
			)
		)
		(property "Val" "4u7"
			(at 106.68 81.915 90)
			(effects
				(font
					(size 1.27 1.27)
					(thickness 0.15)
				)
				(justify left bottom)
			)
		)
		(property "License" "Apache-2.0"
			(at 83.185 96.52 0)
			(effects
				(font
					(size 1.27 1.27)
					(thickness 0.15)
				)
				(justify left bottom)
				(hide yes)
			)
		)
		(property "Author" "Antmicro"
			(at 80.645 96.52 0)
			(effects
				(font
					(size 1.27 1.27)
					(thickness 0.15)
				)
				(justify left bottom)
				(hide yes)
			)
		)
		(property "Voltage" ""
			(at 78.105 96.52 0)
			(effects
				(font
					(size 1.27 1.27)
				)
				(justify left bottom)
				(hide yes)
			)
		)
		(property "Dielectric" ""
			(at 75.565 96.52 0)
			(effects
				(font
					(size 1.27 1.27)
				)
				(justify left bottom)
				(hide yes)
			)
		)
		(pin "1"
		)
		(pin "2"
		)
		(instances
			(project "lpddr4-test-board"
				(path ""
					(reference "C84")
					(unit 1)
				)
			)
		)
	)
	(symbol
		(lib_id "antmicroCapacitors0402:C_4u7_0402")
		(at 99.06 76.2 270)
		(unit 1)
		(exclude_from_sim no)
		(in_bom yes)
		(on_board yes)
		(dnp no)
		(property "Reference" "C83"
			(at 99.695 78.105 90)
			(effects
				(font
					(size 1.27 1.27)
					(thickness 0.15)
				)
				(justify left bottom)
			)
		)
		(property "Value" "C_4u7_0402"
			(at 88.9 96.52 0)
			(effects
				(font
					(size 1.27 1.27)
					(thickness 0.15)
				)
				(justify left bottom)
				(hide yes)
			)
		)
		(property "Footprint" "antmicro-footprints:C_0402_1005Metric"
			(at 86.36 96.52 0)
			(effects
				(font
					(size 1.27 1.27)
					(thickness 0.15)
				)
				(justify left bottom)
				(hide yes)
			)
		)
		(property "Datasheet" " "
			(at 83.82 96.52 0)
			(effects
				(font
					(size 1.27 1.27)
					(thickness 0.15)
				)
				(justify left bottom)
				(hide yes)
			)
		)
		(property "Description" ""
			(at 99.06 76.2 0)
			(effects
				(font
					(size 1.27 1.27)
				)
			)
		)
		(property "Manufacturer" "Murata"
			(at 78.74 96.52 0)
			(effects
				(font
					(size 1.27 1.27)
					(thickness 0.15)
				)
				(justify left bottom)
				(hide yes)
			)
		)
		(property "MPN" "GRM155R61A475MEAAD"
			(at 81.28 96.52 0)
			(effects
				(font
					(size 1.27 1.27)
					(thickness 0.15)
				)
				(justify left bottom)
				(hide yes)
			)
		)
		(property "Val" "4u7"
			(at 99.695 81.915 90)
			(effects
				(font
					(size 1.27 1.27)
					(thickness 0.15)
				)
				(justify left bottom)
			)
		)
		(property "License" "Apache-2.0"
			(at 76.2 96.52 0)
			(effects
				(font
					(size 1.27 1.27)
					(thickness 0.15)
				)
				(justify left bottom)
				(hide yes)
			)
		)
		(property "Author" "Antmicro"
			(at 73.66 96.52 0)
			(effects
				(font
					(size 1.27 1.27)
					(thickness 0.15)
				)
				(justify left bottom)
				(hide yes)
			)
		)
		(property "Voltage" ""
			(at 71.12 96.52 0)
			(effects
				(font
					(size 1.27 1.27)
				)
				(justify left bottom)
				(hide yes)
			)
		)
		(property "Dielectric" ""
			(at 68.58 96.52 0)
			(effects
				(font
					(size 1.27 1.27)
				)
				(justify left bottom)
				(hide yes)
			)
		)
		(pin "1"
		)
		(pin "2"
		)
		(instances
			(project "lpddr4-test-board"
				(path ""
					(reference "C83")
					(unit 1)
				)
			)
		)
	)
	(symbol
		(lib_id "antmicroCapacitorspol:C_Pol_330u_6.3V_KEMET-T520-D")
		(at 92.075 57.15 0)
		(unit 1)
		(exclude_from_sim no)
		(in_bom yes)
		(on_board yes)
		(dnp no)
		(property "Reference" "C81"
			(at 92.71 59.055 0)
			(effects
				(font
					(size 1.27 1.27)
					(thickness 0.15)
				)
				(justify left bottom)
			)
		)
		(property "Value" "C_330u_KEMET_D"
			(at 106.045 62.23 0)
			(effects
				(font
					(size 1.27 1.27)
					(thickness 0.15)
				)
				(justify left bottom)
				(hide yes)
			)
		)
		(property "Footprint" "antmicro-footprints:C_Pol_EIA-D"
			(at 106.045 64.77 0)
			(effects
				(font
					(size 1.27 1.27)
					(thickness 0.15)
				)
				(justify left bottom)
				(hide yes)
			)
		)
		(property "Datasheet" " "
			(at 106.045 67.31 0)
			(effects
				(font
					(size 1.27 1.27)
					(thickness 0.15)
				)
				(justify left bottom)
				(hide yes)
			)
		)
		(property "Description" ""
			(at 92.075 57.15 0)
			(effects
				(font
					(size 1.27 1.27)
				)
			)
		)
		(property "Manufacturer" "KEMET"
			(at 106.045 72.39 0)
			(effects
				(font
					(size 1.27 1.27)
					(thickness 0.15)
				)
				(justify left bottom)
				(hide yes)
			)
		)
		(property "MPN" "T520D337M006ATE045"
			(at 106.045 69.85 0)
			(effects
				(font
					(size 1.27 1.27)
					(thickness 0.15)
				)
				(justify left bottom)
				(hide yes)
			)
		)
		(property "Val" "330u"
			(at 92.71 62.865 0)
			(effects
				(font
					(size 1.27 1.27)
					(thickness 0.15)
				)
				(justify left bottom)
			)
		)
		(property "License" "Apache-2.0"
			(at 106.045 74.93 0)
			(effects
				(font
					(size 1.27 1.27)
					(thickness 0.15)
				)
				(justify left bottom)
				(hide yes)
			)
		)
		(property "Author" "Antmicro"
			(at 106.045 77.47 0)
			(effects
				(font
					(size 1.27 1.27)
					(thickness 0.15)
				)
				(justify left bottom)
				(hide yes)
			)
		)
		(property "Voltage" ""
			(at 106.045 80.01 0)
			(effects
				(font
					(size 1.27 1.27)
				)
				(justify left bottom)
				(hide yes)
			)
		)
		(property "Dielectric" ""
			(at 106.045 82.55 0)
			(effects
				(font
					(size 1.27 1.27)
				)
				(justify left bottom)
				(hide yes)
			)
		)
		(pin "1"
		)
		(pin "2"
		)
		(instances
			(project "lpddr4-test-board"
				(path ""
					(reference "C81")
					(unit 1)
				)
			)
		)
	)
	(symbol
		(lib_id "antmicropower:GND")
		(at 106.045 82.55 0)
		(unit 1)
		(exclude_from_sim no)
		(in_bom yes)
		(on_board yes)
		(dnp no)
		(property "Reference" "#PWR0115"
			(at 114.935 85.09 0)
			(effects
				(font
					(size 1.27 1.27)
					(thickness 0.15)
				)
				(justify left bottom)
				(hide yes)
			)
		)
		(property "Value" "GND"
			(at 104.14 86.995 0)
			(effects
				(font
					(size 1.27 1.27)
					(thickness 0.15)
				)
				(justify left bottom)
			)
		)
		(property "Footprint" ""
			(at 114.935 90.17 0)
			(effects
				(font
					(size 1.27 1.27)
					(thickness 0.15)
				)
				(justify left bottom)
				(hide yes)
			)
		)
		(property "Datasheet" ""
			(at 114.935 95.25 0)
			(effects
				(font
					(size 1.27 1.27)
					(thickness 0.15)
				)
				(justify left bottom)
				(hide yes)
			)
		)
		(property "Description" ""
			(at 106.045 82.55 0)
			(effects
				(font
					(size 1.27 1.27)
				)
			)
		)
		(property "Author" "Antmicro"
			(at 114.935 90.17 0)
			(effects
				(font
					(size 1.27 1.27)
					(thickness 0.15)
				)
				(justify left bottom)
				(hide yes)
			)
		)
		(property "License" "Apache-2.0"
			(at 114.935 92.71 0)
			(effects
				(font
					(size 1.27 1.27)
					(thickness 0.15)
				)
				(justify left bottom)
				(hide yes)
			)
		)
		(pin "1"
		)
		(instances
			(project "lpddr4-test-board"
				(path ""
					(reference "#PWR0115")
					(unit 1)
				)
			)
		)
	)
	(symbol
		(lib_id "antmicropower:GND")
		(at 106.045 234.95 0)
		(unit 1)
		(exclude_from_sim no)
		(in_bom yes)
		(on_board yes)
		(dnp no)
		(property "Reference" "#PWR0219"
			(at 114.935 237.49 0)
			(effects
				(font
					(size 1.27 1.27)
					(thickness 0.15)
				)
				(justify left bottom)
				(hide yes)
			)
		)
		(property "Value" "GND"
			(at 104.14 239.395 0)
			(effects
				(font
					(size 1.27 1.27)
					(thickness 0.15)
				)
				(justify left bottom)
			)
		)
		(property "Footprint" ""
			(at 114.935 242.57 0)
			(effects
				(font
					(size 1.27 1.27)
					(thickness 0.15)
				)
				(justify left bottom)
				(hide yes)
			)
		)
		(property "Datasheet" ""
			(at 114.935 247.65 0)
			(effects
				(font
					(size 1.27 1.27)
					(thickness 0.15)
				)
				(justify left bottom)
				(hide yes)
			)
		)
		(property "Description" ""
			(at 106.045 234.95 0)
			(effects
				(font
					(size 1.27 1.27)
				)
			)
		)
		(property "Author" "Antmicro"
			(at 114.935 242.57 0)
			(effects
				(font
					(size 1.27 1.27)
					(thickness 0.15)
				)
				(justify left bottom)
				(hide yes)
			)
		)
		(property "License" "Apache-2.0"
			(at 114.935 245.11 0)
			(effects
				(font
					(size 1.27 1.27)
					(thickness 0.15)
				)
				(justify left bottom)
				(hide yes)
			)
		)
		(pin "1"
		)
		(instances
			(project "lpddr4-test-board"
				(path ""
					(reference "#PWR0219")
					(unit 1)
				)
			)
		)
	)
	(symbol
		(lib_id "antmicropower:GND")
		(at 147.955 234.95 0)
		(unit 1)
		(exclude_from_sim no)
		(in_bom yes)
		(on_board yes)
		(dnp no)
		(property "Reference" "#PWR0214"
			(at 156.845 237.49 0)
			(effects
				(font
					(size 1.27 1.27)
					(thickness 0.15)
				)
				(justify left bottom)
				(hide yes)
			)
		)
		(property "Value" "GND"
			(at 146.05 239.395 0)
			(effects
				(font
					(size 1.27 1.27)
					(thickness 0.15)
				)
				(justify left bottom)
			)
		)
		(property "Footprint" ""
			(at 156.845 242.57 0)
			(effects
				(font
					(size 1.27 1.27)
					(thickness 0.15)
				)
				(justify left bottom)
				(hide yes)
			)
		)
		(property "Datasheet" ""
			(at 156.845 247.65 0)
			(effects
				(font
					(size 1.27 1.27)
					(thickness 0.15)
				)
				(justify left bottom)
				(hide yes)
			)
		)
		(property "Description" ""
			(at 147.955 234.95 0)
			(effects
				(font
					(size 1.27 1.27)
				)
			)
		)
		(property "Author" "Antmicro"
			(at 156.845 242.57 0)
			(effects
				(font
					(size 1.27 1.27)
					(thickness 0.15)
				)
				(justify left bottom)
				(hide yes)
			)
		)
		(property "License" "Apache-2.0"
			(at 156.845 245.11 0)
			(effects
				(font
					(size 1.27 1.27)
					(thickness 0.15)
				)
				(justify left bottom)
				(hide yes)
			)
		)
		(pin "1"
		)
		(instances
			(project "lpddr4-test-board"
				(path ""
					(reference "#PWR0214")
					(unit 1)
				)
			)
		)
	)
	(symbol
		(lib_id "antmicropower:GND")
		(at 196.85 234.95 0)
		(unit 1)
		(exclude_from_sim no)
		(in_bom yes)
		(on_board yes)
		(dnp no)
		(property "Reference" "#PWR0172"
			(at 205.74 237.49 0)
			(effects
				(font
					(size 1.27 1.27)
					(thickness 0.15)
				)
				(justify left bottom)
				(hide yes)
			)
		)
		(property "Value" "GND"
			(at 194.945 239.395 0)
			(effects
				(font
					(size 1.27 1.27)
					(thickness 0.15)
				)
				(justify left bottom)
			)
		)
		(property "Footprint" ""
			(at 205.74 242.57 0)
			(effects
				(font
					(size 1.27 1.27)
					(thickness 0.15)
				)
				(justify left bottom)
				(hide yes)
			)
		)
		(property "Datasheet" ""
			(at 205.74 247.65 0)
			(effects
				(font
					(size 1.27 1.27)
					(thickness 0.15)
				)
				(justify left bottom)
				(hide yes)
			)
		)
		(property "Description" ""
			(at 196.85 234.95 0)
			(effects
				(font
					(size 1.27 1.27)
				)
			)
		)
		(property "Author" "Antmicro"
			(at 205.74 242.57 0)
			(effects
				(font
					(size 1.27 1.27)
					(thickness 0.15)
				)
				(justify left bottom)
				(hide yes)
			)
		)
		(property "License" "Apache-2.0"
			(at 205.74 245.11 0)
			(effects
				(font
					(size 1.27 1.27)
					(thickness 0.15)
				)
				(justify left bottom)
				(hide yes)
			)
		)
		(pin "1"
		)
		(instances
			(project "lpddr4-test-board"
				(path ""
					(reference "#PWR0172")
					(unit 1)
				)
			)
		)
	)
	(symbol
		(lib_id "antmicroCapacitors0402:C_470n_0402")
		(at 99.06 190.5 270)
		(unit 1)
		(exclude_from_sim no)
		(in_bom yes)
		(on_board yes)
		(dnp no)
		(property "Reference" "C24"
			(at 99.695 192.405 90)
			(effects
				(font
					(size 1.27 1.27)
					(thickness 0.15)
				)
				(justify left bottom)
			)
		)
		(property "Value" "C_470n_0402"
			(at 88.9 210.82 0)
			(effects
				(font
					(size 1.27 1.27)
					(thickness 0.15)
				)
				(justify left bottom)
				(hide yes)
			)
		)
		(property "Footprint" "antmicro-footprints:C_0402_1005Metric"
			(at 86.36 210.82 0)
			(effects
				(font
					(size 1.27 1.27)
					(thickness 0.15)
				)
				(justify left bottom)
				(hide yes)
			)
		)
		(property "Datasheet" " "
			(at 83.82 210.82 0)
			(effects
				(font
					(size 1.27 1.27)
					(thickness 0.15)
				)
				(justify left bottom)
				(hide yes)
			)
		)
		(property "Description" ""
			(at 99.06 190.5 0)
			(effects
				(font
					(size 1.27 1.27)
				)
			)
		)
		(property "Manufacturer" "TDK"
			(at 78.74 210.82 0)
			(effects
				(font
					(size 1.27 1.27)
					(thickness 0.15)
				)
				(justify left bottom)
				(hide yes)
			)
		)
		(property "MPN" "C1005X5R1E474M050BB"
			(at 81.28 210.82 0)
			(effects
				(font
					(size 1.27 1.27)
					(thickness 0.15)
				)
				(justify left bottom)
				(hide yes)
			)
		)
		(property "Val" "470n"
			(at 99.695 196.215 90)
			(effects
				(font
					(size 1.27 1.27)
					(thickness 0.15)
				)
				(justify left bottom)
			)
		)
		(property "License" "Apache-2.0"
			(at 76.2 210.82 0)
			(effects
				(font
					(size 1.27 1.27)
					(thickness 0.15)
				)
				(justify left bottom)
				(hide yes)
			)
		)
		(property "Author" "Antmicro"
			(at 73.66 210.82 0)
			(effects
				(font
					(size 1.27 1.27)
					(thickness 0.15)
				)
				(justify left bottom)
				(hide yes)
			)
		)
		(property "Voltage" ""
			(at 71.12 210.82 0)
			(effects
				(font
					(size 1.27 1.27)
				)
				(justify left bottom)
				(hide yes)
			)
		)
		(property "Dielectric" ""
			(at 68.58 210.82 0)
			(effects
				(font
					(size 1.27 1.27)
				)
				(justify left bottom)
				(hide yes)
			)
		)
		(pin "1"
		)
		(pin "2"
		)
		(instances
			(project "lpddr4-test-board"
				(path ""
					(reference "C24")
					(unit 1)
				)
			)
		)
	)
	(symbol
		(lib_id "antmicropower:GND")
		(at 120.015 139.7 0)
		(unit 1)
		(exclude_from_sim no)
		(in_bom yes)
		(on_board yes)
		(dnp no)
		(property "Reference" "#PWR0200"
			(at 128.905 142.24 0)
			(effects
				(font
					(size 1.27 1.27)
					(thickness 0.15)
				)
				(justify left bottom)
				(hide yes)
			)
		)
		(property "Value" "GND"
			(at 118.11 144.145 0)
			(effects
				(font
					(size 1.27 1.27)
					(thickness 0.15)
				)
				(justify left bottom)
			)
		)
		(property "Footprint" ""
			(at 128.905 147.32 0)
			(effects
				(font
					(size 1.27 1.27)
					(thickness 0.15)
				)
				(justify left bottom)
				(hide yes)
			)
		)
		(property "Datasheet" ""
			(at 128.905 152.4 0)
			(effects
				(font
					(size 1.27 1.27)
					(thickness 0.15)
				)
				(justify left bottom)
				(hide yes)
			)
		)
		(property "Description" ""
			(at 120.015 139.7 0)
			(effects
				(font
					(size 1.27 1.27)
				)
			)
		)
		(property "Author" "Antmicro"
			(at 128.905 147.32 0)
			(effects
				(font
					(size 1.27 1.27)
					(thickness 0.15)
				)
				(justify left bottom)
				(hide yes)
			)
		)
		(property "License" "Apache-2.0"
			(at 128.905 149.86 0)
			(effects
				(font
					(size 1.27 1.27)
					(thickness 0.15)
				)
				(justify left bottom)
				(hide yes)
			)
		)
		(pin "1"
		)
		(instances
			(project "lpddr4-test-board"
				(path ""
					(reference "#PWR0200")
					(unit 1)
				)
			)
		)
	)
	(symbol
		(lib_id "antmicropower:GND")
		(at 113.03 234.95 0)
		(unit 1)
		(exclude_from_sim no)
		(in_bom yes)
		(on_board yes)
		(dnp no)
		(property "Reference" "#PWR0220"
			(at 121.92 237.49 0)
			(effects
				(font
					(size 1.27 1.27)
					(thickness 0.15)
				)
				(justify left bottom)
				(hide yes)
			)
		)
		(property "Value" "GND"
			(at 111.125 239.395 0)
			(effects
				(font
					(size 1.27 1.27)
					(thickness 0.15)
				)
				(justify left bottom)
			)
		)
		(property "Footprint" ""
			(at 121.92 242.57 0)
			(effects
				(font
					(size 1.27 1.27)
					(thickness 0.15)
				)
				(justify left bottom)
				(hide yes)
			)
		)
		(property "Datasheet" ""
			(at 121.92 247.65 0)
			(effects
				(font
					(size 1.27 1.27)
					(thickness 0.15)
				)
				(justify left bottom)
				(hide yes)
			)
		)
		(property "Description" ""
			(at 113.03 234.95 0)
			(effects
				(font
					(size 1.27 1.27)
				)
			)
		)
		(property "Author" "Antmicro"
			(at 121.92 242.57 0)
			(effects
				(font
					(size 1.27 1.27)
					(thickness 0.15)
				)
				(justify left bottom)
				(hide yes)
			)
		)
		(property "License" "Apache-2.0"
			(at 121.92 245.11 0)
			(effects
				(font
					(size 1.27 1.27)
					(thickness 0.15)
				)
				(justify left bottom)
				(hide yes)
			)
		)
		(pin "1"
		)
		(instances
			(project "lpddr4-test-board"
				(path ""
					(reference "#PWR0220")
					(unit 1)
				)
			)
		)
	)
	(symbol
		(lib_id "antmicropower:GND")
		(at 210.82 234.95 0)
		(unit 1)
		(exclude_from_sim no)
		(in_bom yes)
		(on_board yes)
		(dnp no)
		(property "Reference" "#PWR0175"
			(at 219.71 237.49 0)
			(effects
				(font
					(size 1.27 1.27)
					(thickness 0.15)
				)
				(justify left bottom)
				(hide yes)
			)
		)
		(property "Value" "GND"
			(at 208.915 239.395 0)
			(effects
				(font
					(size 1.27 1.27)
					(thickness 0.15)
				)
				(justify left bottom)
			)
		)
		(property "Footprint" ""
			(at 219.71 242.57 0)
			(effects
				(font
					(size 1.27 1.27)
					(thickness 0.15)
				)
				(justify left bottom)
				(hide yes)
			)
		)
		(property "Datasheet" ""
			(at 219.71 247.65 0)
			(effects
				(font
					(size 1.27 1.27)
					(thickness 0.15)
				)
				(justify left bottom)
				(hide yes)
			)
		)
		(property "Description" ""
			(at 210.82 234.95 0)
			(effects
				(font
					(size 1.27 1.27)
				)
			)
		)
		(property "Author" "Antmicro"
			(at 219.71 242.57 0)
			(effects
				(font
					(size 1.27 1.27)
					(thickness 0.15)
				)
				(justify left bottom)
				(hide yes)
			)
		)
		(property "License" "Apache-2.0"
			(at 219.71 245.11 0)
			(effects
				(font
					(size 1.27 1.27)
					(thickness 0.15)
				)
				(justify left bottom)
				(hide yes)
			)
		)
		(pin "1"
		)
		(instances
			(project "lpddr4-test-board"
				(path ""
					(reference "#PWR0175")
					(unit 1)
				)
			)
		)
	)
	(symbol
		(lib_id "antmicropower:GND")
		(at 140.97 234.95 0)
		(unit 1)
		(exclude_from_sim no)
		(in_bom yes)
		(on_board yes)
		(dnp no)
		(property "Reference" "#PWR0215"
			(at 149.86 237.49 0)
			(effects
				(font
					(size 1.27 1.27)
					(thickness 0.15)
				)
				(justify left bottom)
				(hide yes)
			)
		)
		(property "Value" "GND"
			(at 139.065 239.395 0)
			(effects
				(font
					(size 1.27 1.27)
					(thickness 0.15)
				)
				(justify left bottom)
			)
		)
		(property "Footprint" ""
			(at 149.86 242.57 0)
			(effects
				(font
					(size 1.27 1.27)
					(thickness 0.15)
				)
				(justify left bottom)
				(hide yes)
			)
		)
		(property "Datasheet" ""
			(at 149.86 247.65 0)
			(effects
				(font
					(size 1.27 1.27)
					(thickness 0.15)
				)
				(justify left bottom)
				(hide yes)
			)
		)
		(property "Description" ""
			(at 140.97 234.95 0)
			(effects
				(font
					(size 1.27 1.27)
				)
			)
		)
		(property "Author" "Antmicro"
			(at 149.86 242.57 0)
			(effects
				(font
					(size 1.27 1.27)
					(thickness 0.15)
				)
				(justify left bottom)
				(hide yes)
			)
		)
		(property "License" "Apache-2.0"
			(at 149.86 245.11 0)
			(effects
				(font
					(size 1.27 1.27)
					(thickness 0.15)
				)
				(justify left bottom)
				(hide yes)
			)
		)
		(pin "1"
		)
		(instances
			(project "lpddr4-test-board"
				(path ""
					(reference "#PWR0215")
					(unit 1)
				)
			)
		)
	)
	(symbol
		(lib_id "antmicropower:GND")
		(at 92.075 196.85 0)
		(unit 1)
		(exclude_from_sim no)
		(in_bom yes)
		(on_board yes)
		(dnp no)
		(property "Reference" "#PWR0209"
			(at 100.965 199.39 0)
			(effects
				(font
					(size 1.27 1.27)
					(thickness 0.15)
				)
				(justify left bottom)
				(hide yes)
			)
		)
		(property "Value" "GND"
			(at 90.17 201.295 0)
			(effects
				(font
					(size 1.27 1.27)
					(thickness 0.15)
				)
				(justify left bottom)
			)
		)
		(property "Footprint" ""
			(at 100.965 204.47 0)
			(effects
				(font
					(size 1.27 1.27)
					(thickness 0.15)
				)
				(justify left bottom)
				(hide yes)
			)
		)
		(property "Datasheet" ""
			(at 100.965 209.55 0)
			(effects
				(font
					(size 1.27 1.27)
					(thickness 0.15)
				)
				(justify left bottom)
				(hide yes)
			)
		)
		(property "Description" ""
			(at 92.075 196.85 0)
			(effects
				(font
					(size 1.27 1.27)
				)
			)
		)
		(property "Author" "Antmicro"
			(at 100.965 204.47 0)
			(effects
				(font
					(size 1.27 1.27)
					(thickness 0.15)
				)
				(justify left bottom)
				(hide yes)
			)
		)
		(property "License" "Apache-2.0"
			(at 100.965 207.01 0)
			(effects
				(font
					(size 1.27 1.27)
					(thickness 0.15)
				)
				(justify left bottom)
				(hide yes)
			)
		)
		(pin "1"
		)
		(instances
			(project "lpddr4-test-board"
				(path ""
					(reference "#PWR0209")
					(unit 1)
				)
			)
		)
	)
	(symbol
		(lib_id "antmicropower:GND")
		(at 113.03 177.8 0)
		(unit 1)
		(exclude_from_sim no)
		(in_bom yes)
		(on_board yes)
		(dnp no)
		(property "Reference" "#PWR0195"
			(at 121.92 180.34 0)
			(effects
				(font
					(size 1.27 1.27)
					(thickness 0.15)
				)
				(justify left bottom)
				(hide yes)
			)
		)
		(property "Value" "GND"
			(at 111.125 182.245 0)
			(effects
				(font
					(size 1.27 1.27)
					(thickness 0.15)
				)
				(justify left bottom)
			)
		)
		(property "Footprint" ""
			(at 121.92 185.42 0)
			(effects
				(font
					(size 1.27 1.27)
					(thickness 0.15)
				)
				(justify left bottom)
				(hide yes)
			)
		)
		(property "Datasheet" ""
			(at 121.92 190.5 0)
			(effects
				(font
					(size 1.27 1.27)
					(thickness 0.15)
				)
				(justify left bottom)
				(hide yes)
			)
		)
		(property "Description" ""
			(at 113.03 177.8 0)
			(effects
				(font
					(size 1.27 1.27)
				)
			)
		)
		(property "Author" "Antmicro"
			(at 121.92 185.42 0)
			(effects
				(font
					(size 1.27 1.27)
					(thickness 0.15)
				)
				(justify left bottom)
				(hide yes)
			)
		)
		(property "License" "Apache-2.0"
			(at 121.92 187.96 0)
			(effects
				(font
					(size 1.27 1.27)
					(thickness 0.15)
				)
				(justify left bottom)
				(hide yes)
			)
		)
		(pin "1"
		)
		(instances
			(project "lpddr4-test-board"
				(path ""
					(reference "#PWR0195")
					(unit 1)
				)
			)
		)
	)
	(symbol
		(lib_id "antmicropower:GND")
		(at 120.015 234.95 0)
		(unit 1)
		(exclude_from_sim no)
		(in_bom yes)
		(on_board yes)
		(dnp no)
		(property "Reference" "#PWR0221"
			(at 128.905 237.49 0)
			(effects
				(font
					(size 1.27 1.27)
					(thickness 0.15)
				)
				(justify left bottom)
				(hide yes)
			)
		)
		(property "Value" "GND"
			(at 118.11 239.395 0)
			(effects
				(font
					(size 1.27 1.27)
					(thickness 0.15)
				)
				(justify left bottom)
			)
		)
		(property "Footprint" ""
			(at 128.905 242.57 0)
			(effects
				(font
					(size 1.27 1.27)
					(thickness 0.15)
				)
				(justify left bottom)
				(hide yes)
			)
		)
		(property "Datasheet" ""
			(at 128.905 247.65 0)
			(effects
				(font
					(size 1.27 1.27)
					(thickness 0.15)
				)
				(justify left bottom)
				(hide yes)
			)
		)
		(property "Description" ""
			(at 120.015 234.95 0)
			(effects
				(font
					(size 1.27 1.27)
				)
			)
		)
		(property "Author" "Antmicro"
			(at 128.905 242.57 0)
			(effects
				(font
					(size 1.27 1.27)
					(thickness 0.15)
				)
				(justify left bottom)
				(hide yes)
			)
		)
		(property "License" "Apache-2.0"
			(at 128.905 245.11 0)
			(effects
				(font
					(size 1.27 1.27)
					(thickness 0.15)
				)
				(justify left bottom)
				(hide yes)
			)
		)
		(pin "1"
		)
		(instances
			(project "lpddr4-test-board"
				(path ""
					(reference "#PWR0221")
					(unit 1)
				)
			)
		)
	)
	(symbol
		(lib_id "antmicropower:GND")
		(at 161.925 177.8 0)
		(unit 1)
		(exclude_from_sim no)
		(in_bom yes)
		(on_board yes)
		(dnp no)
		(property "Reference" "#PWR0138"
			(at 170.815 180.34 0)
			(effects
				(font
					(size 1.27 1.27)
					(thickness 0.15)
				)
				(justify left bottom)
				(hide yes)
			)
		)
		(property "Value" "GND"
			(at 160.02 182.245 0)
			(effects
				(font
					(size 1.27 1.27)
					(thickness 0.15)
				)
				(justify left bottom)
			)
		)
		(property "Footprint" ""
			(at 170.815 185.42 0)
			(effects
				(font
					(size 1.27 1.27)
					(thickness 0.15)
				)
				(justify left bottom)
				(hide yes)
			)
		)
		(property "Datasheet" ""
			(at 170.815 190.5 0)
			(effects
				(font
					(size 1.27 1.27)
					(thickness 0.15)
				)
				(justify left bottom)
				(hide yes)
			)
		)
		(property "Description" ""
			(at 161.925 177.8 0)
			(effects
				(font
					(size 1.27 1.27)
				)
			)
		)
		(property "Author" "Antmicro"
			(at 170.815 185.42 0)
			(effects
				(font
					(size 1.27 1.27)
					(thickness 0.15)
				)
				(justify left bottom)
				(hide yes)
			)
		)
		(property "License" "Apache-2.0"
			(at 170.815 187.96 0)
			(effects
				(font
					(size 1.27 1.27)
					(thickness 0.15)
				)
				(justify left bottom)
				(hide yes)
			)
		)
		(pin "1"
		)
		(instances
			(project "lpddr4-test-board"
				(path ""
					(reference "#PWR0138")
					(unit 1)
				)
			)
		)
	)
	(symbol
		(lib_id "antmicropower:GND")
		(at 92.075 158.75 0)
		(unit 1)
		(exclude_from_sim no)
		(in_bom yes)
		(on_board yes)
		(dnp no)
		(property "Reference" "#PWR0262"
			(at 100.965 161.29 0)
			(effects
				(font
					(size 1.27 1.27)
					(thickness 0.15)
				)
				(justify left bottom)
				(hide yes)
			)
		)
		(property "Value" "GND"
			(at 90.17 163.195 0)
			(effects
				(font
					(size 1.27 1.27)
					(thickness 0.15)
				)
				(justify left bottom)
			)
		)
		(property "Footprint" ""
			(at 100.965 166.37 0)
			(effects
				(font
					(size 1.27 1.27)
					(thickness 0.15)
				)
				(justify left bottom)
				(hide yes)
			)
		)
		(property "Datasheet" ""
			(at 100.965 171.45 0)
			(effects
				(font
					(size 1.27 1.27)
					(thickness 0.15)
				)
				(justify left bottom)
				(hide yes)
			)
		)
		(property "Description" ""
			(at 92.075 158.75 0)
			(effects
				(font
					(size 1.27 1.27)
				)
			)
		)
		(property "Author" "Antmicro"
			(at 100.965 166.37 0)
			(effects
				(font
					(size 1.27 1.27)
					(thickness 0.15)
				)
				(justify left bottom)
				(hide yes)
			)
		)
		(property "License" "Apache-2.0"
			(at 100.965 168.91 0)
			(effects
				(font
					(size 1.27 1.27)
					(thickness 0.15)
				)
				(justify left bottom)
				(hide yes)
			)
		)
		(pin "1"
		)
		(instances
			(project "lpddr4-test-board"
				(path ""
					(reference "#PWR0262")
					(unit 1)
				)
			)
		)
	)
	(symbol
		(lib_id "antmicropower:GND")
		(at 133.985 234.95 0)
		(unit 1)
		(exclude_from_sim no)
		(in_bom yes)
		(on_board yes)
		(dnp no)
		(property "Reference" "#PWR0216"
			(at 142.875 237.49 0)
			(effects
				(font
					(size 1.27 1.27)
					(thickness 0.15)
				)
				(justify left bottom)
				(hide yes)
			)
		)
		(property "Value" "GND"
			(at 132.08 239.395 0)
			(effects
				(font
					(size 1.27 1.27)
					(thickness 0.15)
				)
				(justify left bottom)
			)
		)
		(property "Footprint" ""
			(at 142.875 242.57 0)
			(effects
				(font
					(size 1.27 1.27)
					(thickness 0.15)
				)
				(justify left bottom)
				(hide yes)
			)
		)
		(property "Datasheet" ""
			(at 142.875 247.65 0)
			(effects
				(font
					(size 1.27 1.27)
					(thickness 0.15)
				)
				(justify left bottom)
				(hide yes)
			)
		)
		(property "Description" ""
			(at 133.985 234.95 0)
			(effects
				(font
					(size 1.27 1.27)
				)
			)
		)
		(property "Author" "Antmicro"
			(at 142.875 242.57 0)
			(effects
				(font
					(size 1.27 1.27)
					(thickness 0.15)
				)
				(justify left bottom)
				(hide yes)
			)
		)
		(property "License" "Apache-2.0"
			(at 142.875 245.11 0)
			(effects
				(font
					(size 1.27 1.27)
					(thickness 0.15)
				)
				(justify left bottom)
				(hide yes)
			)
		)
		(pin "1"
		)
		(instances
			(project "lpddr4-test-board"
				(path ""
					(reference "#PWR0216")
					(unit 1)
				)
			)
		)
	)
	(symbol
		(lib_id "antmicropower:GND")
		(at 154.94 177.8 0)
		(unit 1)
		(exclude_from_sim no)
		(in_bom yes)
		(on_board yes)
		(dnp no)
		(property "Reference" "#PWR0137"
			(at 163.83 180.34 0)
			(effects
				(font
					(size 1.27 1.27)
					(thickness 0.15)
				)
				(justify left bottom)
				(hide yes)
			)
		)
		(property "Value" "GND"
			(at 153.035 182.245 0)
			(effects
				(font
					(size 1.27 1.27)
					(thickness 0.15)
				)
				(justify left bottom)
			)
		)
		(property "Footprint" ""
			(at 163.83 185.42 0)
			(effects
				(font
					(size 1.27 1.27)
					(thickness 0.15)
				)
				(justify left bottom)
				(hide yes)
			)
		)
		(property "Datasheet" ""
			(at 163.83 190.5 0)
			(effects
				(font
					(size 1.27 1.27)
					(thickness 0.15)
				)
				(justify left bottom)
				(hide yes)
			)
		)
		(property "Description" ""
			(at 154.94 177.8 0)
			(effects
				(font
					(size 1.27 1.27)
				)
			)
		)
		(property "Author" "Antmicro"
			(at 163.83 185.42 0)
			(effects
				(font
					(size 1.27 1.27)
					(thickness 0.15)
				)
				(justify left bottom)
				(hide yes)
			)
		)
		(property "License" "Apache-2.0"
			(at 163.83 187.96 0)
			(effects
				(font
					(size 1.27 1.27)
					(thickness 0.15)
				)
				(justify left bottom)
				(hide yes)
			)
		)
		(pin "1"
		)
		(instances
			(project "lpddr4-test-board"
				(path ""
					(reference "#PWR0137")
					(unit 1)
				)
			)
		)
	)
	(symbol
		(lib_id "antmicropower:GND")
		(at 127 234.95 0)
		(unit 1)
		(exclude_from_sim no)
		(in_bom yes)
		(on_board yes)
		(dnp no)
		(property "Reference" "#PWR0217"
			(at 135.89 237.49 0)
			(effects
				(font
					(size 1.27 1.27)
					(thickness 0.15)
				)
				(justify left bottom)
				(hide yes)
			)
		)
		(property "Value" "GND"
			(at 125.095 239.395 0)
			(effects
				(font
					(size 1.27 1.27)
					(thickness 0.15)
				)
				(justify left bottom)
			)
		)
		(property "Footprint" ""
			(at 135.89 242.57 0)
			(effects
				(font
					(size 1.27 1.27)
					(thickness 0.15)
				)
				(justify left bottom)
				(hide yes)
			)
		)
		(property "Datasheet" ""
			(at 135.89 247.65 0)
			(effects
				(font
					(size 1.27 1.27)
					(thickness 0.15)
				)
				(justify left bottom)
				(hide yes)
			)
		)
		(property "Description" ""
			(at 127 234.95 0)
			(effects
				(font
					(size 1.27 1.27)
				)
			)
		)
		(property "Author" "Antmicro"
			(at 135.89 242.57 0)
			(effects
				(font
					(size 1.27 1.27)
					(thickness 0.15)
				)
				(justify left bottom)
				(hide yes)
			)
		)
		(property "License" "Apache-2.0"
			(at 135.89 245.11 0)
			(effects
				(font
					(size 1.27 1.27)
					(thickness 0.15)
				)
				(justify left bottom)
				(hide yes)
			)
		)
		(pin "1"
		)
		(instances
			(project "lpddr4-test-board"
				(path ""
					(reference "#PWR0217")
					(unit 1)
				)
			)
		)
	)
	(symbol
		(lib_id "antmicropower:GND")
		(at 182.88 234.95 0)
		(unit 1)
		(exclude_from_sim no)
		(in_bom yes)
		(on_board yes)
		(dnp no)
		(property "Reference" "#PWR0182"
			(at 191.77 237.49 0)
			(effects
				(font
					(size 1.27 1.27)
					(thickness 0.15)
				)
				(justify left bottom)
				(hide yes)
			)
		)
		(property "Value" "GND"
			(at 180.975 239.395 0)
			(effects
				(font
					(size 1.27 1.27)
					(thickness 0.15)
				)
				(justify left bottom)
			)
		)
		(property "Footprint" ""
			(at 191.77 242.57 0)
			(effects
				(font
					(size 1.27 1.27)
					(thickness 0.15)
				)
				(justify left bottom)
				(hide yes)
			)
		)
		(property "Datasheet" ""
			(at 191.77 247.65 0)
			(effects
				(font
					(size 1.27 1.27)
					(thickness 0.15)
				)
				(justify left bottom)
				(hide yes)
			)
		)
		(property "Description" ""
			(at 182.88 234.95 0)
			(effects
				(font
					(size 1.27 1.27)
				)
			)
		)
		(property "Author" "Antmicro"
			(at 191.77 242.57 0)
			(effects
				(font
					(size 1.27 1.27)
					(thickness 0.15)
				)
				(justify left bottom)
				(hide yes)
			)
		)
		(property "License" "Apache-2.0"
			(at 191.77 245.11 0)
			(effects
				(font
					(size 1.27 1.27)
					(thickness 0.15)
				)
				(justify left bottom)
				(hide yes)
			)
		)
		(pin "1"
		)
		(instances
			(project "lpddr4-test-board"
				(path ""
					(reference "#PWR0182")
					(unit 1)
				)
			)
		)
	)
	(symbol
		(lib_id "antmicropower:GND")
		(at 99.06 177.8 0)
		(unit 1)
		(exclude_from_sim no)
		(in_bom yes)
		(on_board yes)
		(dnp no)
		(property "Reference" "#PWR0211"
			(at 107.95 180.34 0)
			(effects
				(font
					(size 1.27 1.27)
					(thickness 0.15)
				)
				(justify left bottom)
				(hide yes)
			)
		)
		(property "Value" "GND"
			(at 97.155 182.245 0)
			(effects
				(font
					(size 1.27 1.27)
					(thickness 0.15)
				)
				(justify left bottom)
			)
		)
		(property "Footprint" ""
			(at 107.95 185.42 0)
			(effects
				(font
					(size 1.27 1.27)
					(thickness 0.15)
				)
				(justify left bottom)
				(hide yes)
			)
		)
		(property "Datasheet" ""
			(at 107.95 190.5 0)
			(effects
				(font
					(size 1.27 1.27)
					(thickness 0.15)
				)
				(justify left bottom)
				(hide yes)
			)
		)
		(property "Description" ""
			(at 99.06 177.8 0)
			(effects
				(font
					(size 1.27 1.27)
				)
			)
		)
		(property "Author" "Antmicro"
			(at 107.95 185.42 0)
			(effects
				(font
					(size 1.27 1.27)
					(thickness 0.15)
				)
				(justify left bottom)
				(hide yes)
			)
		)
		(property "License" "Apache-2.0"
			(at 107.95 187.96 0)
			(effects
				(font
					(size 1.27 1.27)
					(thickness 0.15)
				)
				(justify left bottom)
				(hide yes)
			)
		)
		(pin "1"
		)
		(instances
			(project "lpddr4-test-board"
				(path ""
					(reference "#PWR0211")
					(unit 1)
				)
			)
		)
	)
	(symbol
		(lib_id "antmicropower:GND")
		(at 161.925 234.95 0)
		(unit 1)
		(exclude_from_sim no)
		(in_bom yes)
		(on_board yes)
		(dnp no)
		(property "Reference" "#PWR0168"
			(at 170.815 237.49 0)
			(effects
				(font
					(size 1.27 1.27)
					(thickness 0.15)
				)
				(justify left bottom)
				(hide yes)
			)
		)
		(property "Value" "GND"
			(at 160.02 239.395 0)
			(effects
				(font
					(size 1.27 1.27)
					(thickness 0.15)
				)
				(justify left bottom)
			)
		)
		(property "Footprint" ""
			(at 170.815 242.57 0)
			(effects
				(font
					(size 1.27 1.27)
					(thickness 0.15)
				)
				(justify left bottom)
				(hide yes)
			)
		)
		(property "Datasheet" ""
			(at 170.815 247.65 0)
			(effects
				(font
					(size 1.27 1.27)
					(thickness 0.15)
				)
				(justify left bottom)
				(hide yes)
			)
		)
		(property "Description" ""
			(at 161.925 234.95 0)
			(effects
				(font
					(size 1.27 1.27)
				)
			)
		)
		(property "Author" "Antmicro"
			(at 170.815 242.57 0)
			(effects
				(font
					(size 1.27 1.27)
					(thickness 0.15)
				)
				(justify left bottom)
				(hide yes)
			)
		)
		(property "License" "Apache-2.0"
			(at 170.815 245.11 0)
			(effects
				(font
					(size 1.27 1.27)
					(thickness 0.15)
				)
				(justify left bottom)
				(hide yes)
			)
		)
		(pin "1"
		)
		(instances
			(project "lpddr4-test-board"
				(path ""
					(reference "#PWR0168")
					(unit 1)
				)
			)
		)
	)
	(symbol
		(lib_id "antmicropower:GND")
		(at 99.06 139.7 0)
		(unit 1)
		(exclude_from_sim no)
		(in_bom yes)
		(on_board yes)
		(dnp no)
		(property "Reference" "#PWR0250"
			(at 107.95 142.24 0)
			(effects
				(font
					(size 1.27 1.27)
					(thickness 0.15)
				)
				(justify left bottom)
				(hide yes)
			)
		)
		(property "Value" "GND"
			(at 97.155 144.145 0)
			(effects
				(font
					(size 1.27 1.27)
					(thickness 0.15)
				)
				(justify left bottom)
			)
		)
		(property "Footprint" ""
			(at 107.95 147.32 0)
			(effects
				(font
					(size 1.27 1.27)
					(thickness 0.15)
				)
				(justify left bottom)
				(hide yes)
			)
		)
		(property "Datasheet" ""
			(at 107.95 152.4 0)
			(effects
				(font
					(size 1.27 1.27)
					(thickness 0.15)
				)
				(justify left bottom)
				(hide yes)
			)
		)
		(property "Description" ""
			(at 99.06 139.7 0)
			(effects
				(font
					(size 1.27 1.27)
				)
			)
		)
		(property "Author" "Antmicro"
			(at 107.95 147.32 0)
			(effects
				(font
					(size 1.27 1.27)
					(thickness 0.15)
				)
				(justify left bottom)
				(hide yes)
			)
		)
		(property "License" "Apache-2.0"
			(at 107.95 149.86 0)
			(effects
				(font
					(size 1.27 1.27)
					(thickness 0.15)
				)
				(justify left bottom)
				(hide yes)
			)
		)
		(pin "1"
		)
		(instances
			(project "lpddr4-test-board"
				(path ""
					(reference "#PWR0250")
					(unit 1)
				)
			)
		)
	)
	(symbol
		(lib_id "antmicropower:GND")
		(at 113.03 139.7 0)
		(unit 1)
		(exclude_from_sim no)
		(in_bom yes)
		(on_board yes)
		(dnp no)
		(property "Reference" "#PWR0201"
			(at 121.92 142.24 0)
			(effects
				(font
					(size 1.27 1.27)
					(thickness 0.15)
				)
				(justify left bottom)
				(hide yes)
			)
		)
		(property "Value" "GND"
			(at 111.125 144.145 0)
			(effects
				(font
					(size 1.27 1.27)
					(thickness 0.15)
				)
				(justify left bottom)
			)
		)
		(property "Footprint" ""
			(at 121.92 147.32 0)
			(effects
				(font
					(size 1.27 1.27)
					(thickness 0.15)
				)
				(justify left bottom)
				(hide yes)
			)
		)
		(property "Datasheet" ""
			(at 121.92 152.4 0)
			(effects
				(font
					(size 1.27 1.27)
					(thickness 0.15)
				)
				(justify left bottom)
				(hide yes)
			)
		)
		(property "Description" ""
			(at 113.03 139.7 0)
			(effects
				(font
					(size 1.27 1.27)
				)
			)
		)
		(property "Author" "Antmicro"
			(at 121.92 147.32 0)
			(effects
				(font
					(size 1.27 1.27)
					(thickness 0.15)
				)
				(justify left bottom)
				(hide yes)
			)
		)
		(property "License" "Apache-2.0"
			(at 121.92 149.86 0)
			(effects
				(font
					(size 1.27 1.27)
					(thickness 0.15)
				)
				(justify left bottom)
				(hide yes)
			)
		)
		(pin "1"
		)
		(instances
			(project "lpddr4-test-board"
				(path ""
					(reference "#PWR0201")
					(unit 1)
				)
			)
		)
	)
	(symbol
		(lib_id "antmicropower:GND")
		(at 147.955 139.7 0)
		(unit 1)
		(exclude_from_sim no)
		(in_bom yes)
		(on_board yes)
		(dnp no)
		(property "Reference" "#PWR0203"
			(at 156.845 142.24 0)
			(effects
				(font
					(size 1.27 1.27)
					(thickness 0.15)
				)
				(justify left bottom)
				(hide yes)
			)
		)
		(property "Value" "GND"
			(at 146.05 144.145 0)
			(effects
				(font
					(size 1.27 1.27)
					(thickness 0.15)
				)
				(justify left bottom)
			)
		)
		(property "Footprint" ""
			(at 156.845 147.32 0)
			(effects
				(font
					(size 1.27 1.27)
					(thickness 0.15)
				)
				(justify left bottom)
				(hide yes)
			)
		)
		(property "Datasheet" ""
			(at 156.845 152.4 0)
			(effects
				(font
					(size 1.27 1.27)
					(thickness 0.15)
				)
				(justify left bottom)
				(hide yes)
			)
		)
		(property "Description" ""
			(at 147.955 139.7 0)
			(effects
				(font
					(size 1.27 1.27)
				)
			)
		)
		(property "Author" "Antmicro"
			(at 156.845 147.32 0)
			(effects
				(font
					(size 1.27 1.27)
					(thickness 0.15)
				)
				(justify left bottom)
				(hide yes)
			)
		)
		(property "License" "Apache-2.0"
			(at 156.845 149.86 0)
			(effects
				(font
					(size 1.27 1.27)
					(thickness 0.15)
				)
				(justify left bottom)
				(hide yes)
			)
		)
		(pin "1"
		)
		(instances
			(project "lpddr4-test-board"
				(path ""
					(reference "#PWR0203")
					(unit 1)
				)
			)
		)
	)
	(symbol
		(lib_id "antmicropower:GND")
		(at 168.91 177.8 0)
		(unit 1)
		(exclude_from_sim no)
		(in_bom yes)
		(on_board yes)
		(dnp no)
		(property "Reference" "#PWR0140"
			(at 177.8 180.34 0)
			(effects
				(font
					(size 1.27 1.27)
					(thickness 0.15)
				)
				(justify left bottom)
				(hide yes)
			)
		)
		(property "Value" "GND"
			(at 167.005 182.245 0)
			(effects
				(font
					(size 1.27 1.27)
					(thickness 0.15)
				)
				(justify left bottom)
			)
		)
		(property "Footprint" ""
			(at 177.8 185.42 0)
			(effects
				(font
					(size 1.27 1.27)
					(thickness 0.15)
				)
				(justify left bottom)
				(hide yes)
			)
		)
		(property "Datasheet" ""
			(at 177.8 190.5 0)
			(effects
				(font
					(size 1.27 1.27)
					(thickness 0.15)
				)
				(justify left bottom)
				(hide yes)
			)
		)
		(property "Description" ""
			(at 168.91 177.8 0)
			(effects
				(font
					(size 1.27 1.27)
				)
			)
		)
		(property "Author" "Antmicro"
			(at 177.8 185.42 0)
			(effects
				(font
					(size 1.27 1.27)
					(thickness 0.15)
				)
				(justify left bottom)
				(hide yes)
			)
		)
		(property "License" "Apache-2.0"
			(at 177.8 187.96 0)
			(effects
				(font
					(size 1.27 1.27)
					(thickness 0.15)
				)
				(justify left bottom)
				(hide yes)
			)
		)
		(pin "1"
		)
		(instances
			(project "lpddr4-test-board"
				(path ""
					(reference "#PWR0140")
					(unit 1)
				)
			)
		)
	)
	(symbol
		(lib_id "antmicropower:GND")
		(at 99.06 120.65 0)
		(unit 1)
		(exclude_from_sim no)
		(in_bom yes)
		(on_board yes)
		(dnp no)
		(property "Reference" "#PWR0204"
			(at 107.95 123.19 0)
			(effects
				(font
					(size 1.27 1.27)
					(thickness 0.15)
				)
				(justify left bottom)
				(hide yes)
			)
		)
		(property "Value" "GND"
			(at 97.155 125.095 0)
			(effects
				(font
					(size 1.27 1.27)
					(thickness 0.15)
				)
				(justify left bottom)
			)
		)
		(property "Footprint" ""
			(at 107.95 128.27 0)
			(effects
				(font
					(size 1.27 1.27)
					(thickness 0.15)
				)
				(justify left bottom)
				(hide yes)
			)
		)
		(property "Datasheet" ""
			(at 107.95 133.35 0)
			(effects
				(font
					(size 1.27 1.27)
					(thickness 0.15)
				)
				(justify left bottom)
				(hide yes)
			)
		)
		(property "Description" ""
			(at 99.06 120.65 0)
			(effects
				(font
					(size 1.27 1.27)
				)
			)
		)
		(property "Author" "Antmicro"
			(at 107.95 128.27 0)
			(effects
				(font
					(size 1.27 1.27)
					(thickness 0.15)
				)
				(justify left bottom)
				(hide yes)
			)
		)
		(property "License" "Apache-2.0"
			(at 107.95 130.81 0)
			(effects
				(font
					(size 1.27 1.27)
					(thickness 0.15)
				)
				(justify left bottom)
				(hide yes)
			)
		)
		(pin "1"
		)
		(instances
			(project "lpddr4-test-board"
				(path ""
					(reference "#PWR0204")
					(unit 1)
				)
			)
		)
	)
	(symbol
		(lib_id "antmicropower:GND")
		(at 120.015 120.65 0)
		(unit 1)
		(exclude_from_sim no)
		(in_bom yes)
		(on_board yes)
		(dnp no)
		(property "Reference" "#PWR0197"
			(at 128.905 123.19 0)
			(effects
				(font
					(size 1.27 1.27)
					(thickness 0.15)
				)
				(justify left bottom)
				(hide yes)
			)
		)
		(property "Value" "GND"
			(at 118.11 125.095 0)
			(effects
				(font
					(size 1.27 1.27)
					(thickness 0.15)
				)
				(justify left bottom)
			)
		)
		(property "Footprint" ""
			(at 128.905 128.27 0)
			(effects
				(font
					(size 1.27 1.27)
					(thickness 0.15)
				)
				(justify left bottom)
				(hide yes)
			)
		)
		(property "Datasheet" ""
			(at 128.905 133.35 0)
			(effects
				(font
					(size 1.27 1.27)
					(thickness 0.15)
				)
				(justify left bottom)
				(hide yes)
			)
		)
		(property "Description" ""
			(at 120.015 120.65 0)
			(effects
				(font
					(size 1.27 1.27)
				)
			)
		)
		(property "Author" "Antmicro"
			(at 128.905 128.27 0)
			(effects
				(font
					(size 1.27 1.27)
					(thickness 0.15)
				)
				(justify left bottom)
				(hide yes)
			)
		)
		(property "License" "Apache-2.0"
			(at 128.905 130.81 0)
			(effects
				(font
					(size 1.27 1.27)
					(thickness 0.15)
				)
				(justify left bottom)
				(hide yes)
			)
		)
		(pin "1"
		)
		(instances
			(project "lpddr4-test-board"
				(path ""
					(reference "#PWR0197")
					(unit 1)
				)
			)
		)
	)
	(symbol
		(lib_id "antmicropower:GND")
		(at 140.97 139.7 0)
		(unit 1)
		(exclude_from_sim no)
		(in_bom yes)
		(on_board yes)
		(dnp no)
		(property "Reference" "#PWR0202"
			(at 149.86 142.24 0)
			(effects
				(font
					(size 1.27 1.27)
					(thickness 0.15)
				)
				(justify left bottom)
				(hide yes)
			)
		)
		(property "Value" "GND"
			(at 139.065 144.145 0)
			(effects
				(font
					(size 1.27 1.27)
					(thickness 0.15)
				)
				(justify left bottom)
			)
		)
		(property "Footprint" ""
			(at 149.86 147.32 0)
			(effects
				(font
					(size 1.27 1.27)
					(thickness 0.15)
				)
				(justify left bottom)
				(hide yes)
			)
		)
		(property "Datasheet" ""
			(at 149.86 152.4 0)
			(effects
				(font
					(size 1.27 1.27)
					(thickness 0.15)
				)
				(justify left bottom)
				(hide yes)
			)
		)
		(property "Description" ""
			(at 140.97 139.7 0)
			(effects
				(font
					(size 1.27 1.27)
				)
			)
		)
		(property "Author" "Antmicro"
			(at 149.86 147.32 0)
			(effects
				(font
					(size 1.27 1.27)
					(thickness 0.15)
				)
				(justify left bottom)
				(hide yes)
			)
		)
		(property "License" "Apache-2.0"
			(at 149.86 149.86 0)
			(effects
				(font
					(size 1.27 1.27)
					(thickness 0.15)
				)
				(justify left bottom)
				(hide yes)
			)
		)
		(pin "1"
		)
		(instances
			(project "lpddr4-test-board"
				(path ""
					(reference "#PWR0202")
					(unit 1)
				)
			)
		)
	)
	(symbol
		(lib_id "antmicropower:GND")
		(at 154.94 234.95 0)
		(unit 1)
		(exclude_from_sim no)
		(in_bom yes)
		(on_board yes)
		(dnp no)
		(property "Reference" "#PWR0169"
			(at 163.83 237.49 0)
			(effects
				(font
					(size 1.27 1.27)
					(thickness 0.15)
				)
				(justify left bottom)
				(hide yes)
			)
		)
		(property "Value" "GND"
			(at 153.035 239.395 0)
			(effects
				(font
					(size 1.27 1.27)
					(thickness 0.15)
				)
				(justify left bottom)
			)
		)
		(property "Footprint" ""
			(at 163.83 242.57 0)
			(effects
				(font
					(size 1.27 1.27)
					(thickness 0.15)
				)
				(justify left bottom)
				(hide yes)
			)
		)
		(property "Datasheet" ""
			(at 163.83 247.65 0)
			(effects
				(font
					(size 1.27 1.27)
					(thickness 0.15)
				)
				(justify left bottom)
				(hide yes)
			)
		)
		(property "Description" ""
			(at 154.94 234.95 0)
			(effects
				(font
					(size 1.27 1.27)
				)
			)
		)
		(property "Author" "Antmicro"
			(at 163.83 242.57 0)
			(effects
				(font
					(size 1.27 1.27)
					(thickness 0.15)
				)
				(justify left bottom)
				(hide yes)
			)
		)
		(property "License" "Apache-2.0"
			(at 163.83 245.11 0)
			(effects
				(font
					(size 1.27 1.27)
					(thickness 0.15)
				)
				(justify left bottom)
				(hide yes)
			)
		)
		(pin "1"
		)
		(instances
			(project "lpddr4-test-board"
				(path ""
					(reference "#PWR0169")
					(unit 1)
				)
			)
		)
	)
	(symbol
		(lib_id "antmicropower:GND")
		(at 120.015 177.8 0)
		(unit 1)
		(exclude_from_sim no)
		(in_bom yes)
		(on_board yes)
		(dnp no)
		(property "Reference" "#PWR0194"
			(at 128.905 180.34 0)
			(effects
				(font
					(size 1.27 1.27)
					(thickness 0.15)
				)
				(justify left bottom)
				(hide yes)
			)
		)
		(property "Value" "GND"
			(at 118.11 182.245 0)
			(effects
				(font
					(size 1.27 1.27)
					(thickness 0.15)
				)
				(justify left bottom)
			)
		)
		(property "Footprint" ""
			(at 128.905 185.42 0)
			(effects
				(font
					(size 1.27 1.27)
					(thickness 0.15)
				)
				(justify left bottom)
				(hide yes)
			)
		)
		(property "Datasheet" ""
			(at 128.905 190.5 0)
			(effects
				(font
					(size 1.27 1.27)
					(thickness 0.15)
				)
				(justify left bottom)
				(hide yes)
			)
		)
		(property "Description" ""
			(at 120.015 177.8 0)
			(effects
				(font
					(size 1.27 1.27)
				)
			)
		)
		(property "Author" "Antmicro"
			(at 128.905 185.42 0)
			(effects
				(font
					(size 1.27 1.27)
					(thickness 0.15)
				)
				(justify left bottom)
				(hide yes)
			)
		)
		(property "License" "Apache-2.0"
			(at 128.905 187.96 0)
			(effects
				(font
					(size 1.27 1.27)
					(thickness 0.15)
				)
				(justify left bottom)
				(hide yes)
			)
		)
		(pin "1"
		)
		(instances
			(project "lpddr4-test-board"
				(path ""
					(reference "#PWR0194")
					(unit 1)
				)
			)
		)
	)
	(symbol
		(lib_id "antmicropower:GND")
		(at 189.865 234.95 0)
		(unit 1)
		(exclude_from_sim no)
		(in_bom yes)
		(on_board yes)
		(dnp no)
		(property "Reference" "#PWR0183"
			(at 198.755 237.49 0)
			(effects
				(font
					(size 1.27 1.27)
					(thickness 0.15)
				)
				(justify left bottom)
				(hide yes)
			)
		)
		(property "Value" "GND"
			(at 187.96 239.395 0)
			(effects
				(font
					(size 1.27 1.27)
					(thickness 0.15)
				)
				(justify left bottom)
			)
		)
		(property "Footprint" ""
			(at 198.755 242.57 0)
			(effects
				(font
					(size 1.27 1.27)
					(thickness 0.15)
				)
				(justify left bottom)
				(hide yes)
			)
		)
		(property "Datasheet" ""
			(at 198.755 247.65 0)
			(effects
				(font
					(size 1.27 1.27)
					(thickness 0.15)
				)
				(justify left bottom)
				(hide yes)
			)
		)
		(property "Description" ""
			(at 189.865 234.95 0)
			(effects
				(font
					(size 1.27 1.27)
				)
			)
		)
		(property "Author" "Antmicro"
			(at 198.755 242.57 0)
			(effects
				(font
					(size 1.27 1.27)
					(thickness 0.15)
				)
				(justify left bottom)
				(hide yes)
			)
		)
		(property "License" "Apache-2.0"
			(at 198.755 245.11 0)
			(effects
				(font
					(size 1.27 1.27)
					(thickness 0.15)
				)
				(justify left bottom)
				(hide yes)
			)
		)
		(pin "1"
		)
		(instances
			(project "lpddr4-test-board"
				(path ""
					(reference "#PWR0183")
					(unit 1)
				)
			)
		)
	)
	(symbol
		(lib_id "antmicropower:GND")
		(at 106.045 177.8 0)
		(unit 1)
		(exclude_from_sim no)
		(in_bom yes)
		(on_board yes)
		(dnp no)
		(property "Reference" "#PWR0186"
			(at 114.935 180.34 0)
			(effects
				(font
					(size 1.27 1.27)
					(thickness 0.15)
				)
				(justify left bottom)
				(hide yes)
			)
		)
		(property "Value" "GND"
			(at 104.14 182.245 0)
			(effects
				(font
					(size 1.27 1.27)
					(thickness 0.15)
				)
				(justify left bottom)
			)
		)
		(property "Footprint" ""
			(at 114.935 185.42 0)
			(effects
				(font
					(size 1.27 1.27)
					(thickness 0.15)
				)
				(justify left bottom)
				(hide yes)
			)
		)
		(property "Datasheet" ""
			(at 114.935 190.5 0)
			(effects
				(font
					(size 1.27 1.27)
					(thickness 0.15)
				)
				(justify left bottom)
				(hide yes)
			)
		)
		(property "Description" ""
			(at 106.045 177.8 0)
			(effects
				(font
					(size 1.27 1.27)
				)
			)
		)
		(property "Author" "Antmicro"
			(at 114.935 185.42 0)
			(effects
				(font
					(size 1.27 1.27)
					(thickness 0.15)
				)
				(justify left bottom)
				(hide yes)
			)
		)
		(property "License" "Apache-2.0"
			(at 114.935 187.96 0)
			(effects
				(font
					(size 1.27 1.27)
					(thickness 0.15)
				)
				(justify left bottom)
				(hide yes)
			)
		)
		(pin "1"
		)
		(instances
			(project "lpddr4-test-board"
				(path ""
					(reference "#PWR0186")
					(unit 1)
				)
			)
		)
	)
	(symbol
		(lib_id "antmicropower:GND")
		(at 133.985 139.7 0)
		(unit 1)
		(exclude_from_sim no)
		(in_bom yes)
		(on_board yes)
		(dnp no)
		(property "Reference" "#PWR0199"
			(at 142.875 142.24 0)
			(effects
				(font
					(size 1.27 1.27)
					(thickness 0.15)
				)
				(justify left bottom)
				(hide yes)
			)
		)
		(property "Value" "GND"
			(at 132.08 144.145 0)
			(effects
				(font
					(size 1.27 1.27)
					(thickness 0.15)
				)
				(justify left bottom)
			)
		)
		(property "Footprint" ""
			(at 142.875 147.32 0)
			(effects
				(font
					(size 1.27 1.27)
					(thickness 0.15)
				)
				(justify left bottom)
				(hide yes)
			)
		)
		(property "Datasheet" ""
			(at 142.875 152.4 0)
			(effects
				(font
					(size 1.27 1.27)
					(thickness 0.15)
				)
				(justify left bottom)
				(hide yes)
			)
		)
		(property "Description" ""
			(at 133.985 139.7 0)
			(effects
				(font
					(size 1.27 1.27)
				)
			)
		)
		(property "Author" "Antmicro"
			(at 142.875 147.32 0)
			(effects
				(font
					(size 1.27 1.27)
					(thickness 0.15)
				)
				(justify left bottom)
				(hide yes)
			)
		)
		(property "License" "Apache-2.0"
			(at 142.875 149.86 0)
			(effects
				(font
					(size 1.27 1.27)
					(thickness 0.15)
				)
				(justify left bottom)
				(hide yes)
			)
		)
		(pin "1"
		)
		(instances
			(project "lpddr4-test-board"
				(path ""
					(reference "#PWR0199")
					(unit 1)
				)
			)
		)
	)
	(symbol
		(lib_id "antmicroCapacitors0603:C_47u_0603")
		(at 92.075 190.5 270)
		(unit 1)
		(exclude_from_sim no)
		(in_bom yes)
		(on_board yes)
		(dnp no)
		(property "Reference" "C23"
			(at 92.71 192.405 90)
			(effects
				(font
					(size 1.27 1.27)
					(thickness 0.15)
				)
				(justify left bottom)
			)
		)
		(property "Value" "C_47u_0603"
			(at 81.915 210.82 0)
			(effects
				(font
					(size 1.27 1.27)
					(thickness 0.15)
				)
				(justify left bottom)
				(hide yes)
			)
		)
		(property "Footprint" "antmicro-footprints:C_0603_1608Metric"
			(at 79.375 210.82 0)
			(effects
				(font
					(size 1.27 1.27)
					(thickness 0.15)
				)
				(justify left bottom)
				(hide yes)
			)
		)
		(property "Datasheet" " "
			(at 76.835 210.82 0)
			(effects
				(font
					(size 1.27 1.27)
					(thickness 0.15)
				)
				(justify left bottom)
				(hide yes)
			)
		)
		(property "Description" ""
			(at 92.075 190.5 0)
			(effects
				(font
					(size 1.27 1.27)
				)
			)
		)
		(property "Manufacturer" "Murata"
			(at 71.755 210.82 0)
			(effects
				(font
					(size 1.27 1.27)
					(thickness 0.15)
				)
				(justify left bottom)
				(hide yes)
			)
		)
		(property "MPN" "GRM188R60J476ME15D"
			(at 74.295 210.82 0)
			(effects
				(font
					(size 1.27 1.27)
					(thickness 0.15)
				)
				(justify left bottom)
				(hide yes)
			)
		)
		(property "Val" "47u"
			(at 92.71 196.215 90)
			(effects
				(font
					(size 1.27 1.27)
					(thickness 0.15)
				)
				(justify left bottom)
			)
		)
		(property "License" "Apache-2.0"
			(at 69.215 210.82 0)
			(effects
				(font
					(size 1.27 1.27)
					(thickness 0.15)
				)
				(justify left bottom)
				(hide yes)
			)
		)
		(property "Author" "Antmicro"
			(at 66.675 210.82 0)
			(effects
				(font
					(size 1.27 1.27)
					(thickness 0.15)
				)
				(justify left bottom)
				(hide yes)
			)
		)
		(property "Voltage" ""
			(at 64.135 210.82 0)
			(effects
				(font
					(size 1.27 1.27)
				)
				(justify left bottom)
				(hide yes)
			)
		)
		(property "Dielectric" ""
			(at 61.595 210.82 0)
			(effects
				(font
					(size 1.27 1.27)
				)
				(justify left bottom)
				(hide yes)
			)
		)
		(pin "1"
		)
		(pin "2"
		)
		(instances
			(project "lpddr4-test-board"
				(path ""
					(reference "C23")
					(unit 1)
				)
			)
		)
	)
	(symbol
		(lib_id "antmicropower:GND")
		(at 168.91 234.95 0)
		(unit 1)
		(exclude_from_sim no)
		(in_bom yes)
		(on_board yes)
		(dnp no)
		(property "Reference" "#PWR0184"
			(at 177.8 237.49 0)
			(effects
				(font
					(size 1.27 1.27)
					(thickness 0.15)
				)
				(justify left bottom)
				(hide yes)
			)
		)
		(property "Value" "GND"
			(at 167.005 239.395 0)
			(effects
				(font
					(size 1.27 1.27)
					(thickness 0.15)
				)
				(justify left bottom)
			)
		)
		(property "Footprint" ""
			(at 177.8 242.57 0)
			(effects
				(font
					(size 1.27 1.27)
					(thickness 0.15)
				)
				(justify left bottom)
				(hide yes)
			)
		)
		(property "Datasheet" ""
			(at 177.8 247.65 0)
			(effects
				(font
					(size 1.27 1.27)
					(thickness 0.15)
				)
				(justify left bottom)
				(hide yes)
			)
		)
		(property "Description" ""
			(at 168.91 234.95 0)
			(effects
				(font
					(size 1.27 1.27)
				)
			)
		)
		(property "Author" "Antmicro"
			(at 177.8 242.57 0)
			(effects
				(font
					(size 1.27 1.27)
					(thickness 0.15)
				)
				(justify left bottom)
				(hide yes)
			)
		)
		(property "License" "Apache-2.0"
			(at 177.8 245.11 0)
			(effects
				(font
					(size 1.27 1.27)
					(thickness 0.15)
				)
				(justify left bottom)
				(hide yes)
			)
		)
		(pin "1"
		)
		(instances
			(project "lpddr4-test-board"
				(path ""
					(reference "#PWR0184")
					(unit 1)
				)
			)
		)
	)
	(symbol
		(lib_id "antmicropower:GND")
		(at 106.045 120.65 0)
		(unit 1)
		(exclude_from_sim no)
		(in_bom yes)
		(on_board yes)
		(dnp no)
		(property "Reference" "#PWR0207"
			(at 114.935 123.19 0)
			(effects
				(font
					(size 1.27 1.27)
					(thickness 0.15)
				)
				(justify left bottom)
				(hide yes)
			)
		)
		(property "Value" "GND"
			(at 104.14 125.095 0)
			(effects
				(font
					(size 1.27 1.27)
					(thickness 0.15)
				)
				(justify left bottom)
			)
		)
		(property "Footprint" ""
			(at 114.935 128.27 0)
			(effects
				(font
					(size 1.27 1.27)
					(thickness 0.15)
				)
				(justify left bottom)
				(hide yes)
			)
		)
		(property "Datasheet" ""
			(at 114.935 133.35 0)
			(effects
				(font
					(size 1.27 1.27)
					(thickness 0.15)
				)
				(justify left bottom)
				(hide yes)
			)
		)
		(property "Description" ""
			(at 106.045 120.65 0)
			(effects
				(font
					(size 1.27 1.27)
				)
			)
		)
		(property "Author" "Antmicro"
			(at 114.935 128.27 0)
			(effects
				(font
					(size 1.27 1.27)
					(thickness 0.15)
				)
				(justify left bottom)
				(hide yes)
			)
		)
		(property "License" "Apache-2.0"
			(at 114.935 130.81 0)
			(effects
				(font
					(size 1.27 1.27)
					(thickness 0.15)
				)
				(justify left bottom)
				(hide yes)
			)
		)
		(pin "1"
		)
		(instances
			(project "lpddr4-test-board"
				(path ""
					(reference "#PWR0207")
					(unit 1)
				)
			)
		)
	)
	(symbol
		(lib_id "antmicropower:GND")
		(at 133.985 177.8 0)
		(unit 1)
		(exclude_from_sim no)
		(in_bom yes)
		(on_board yes)
		(dnp no)
		(property "Reference" "#PWR0191"
			(at 142.875 180.34 0)
			(effects
				(font
					(size 1.27 1.27)
					(thickness 0.15)
				)
				(justify left bottom)
				(hide yes)
			)
		)
		(property "Value" "GND"
			(at 132.08 182.245 0)
			(effects
				(font
					(size 1.27 1.27)
					(thickness 0.15)
				)
				(justify left bottom)
			)
		)
		(property "Footprint" ""
			(at 142.875 185.42 0)
			(effects
				(font
					(size 1.27 1.27)
					(thickness 0.15)
				)
				(justify left bottom)
				(hide yes)
			)
		)
		(property "Datasheet" ""
			(at 142.875 190.5 0)
			(effects
				(font
					(size 1.27 1.27)
					(thickness 0.15)
				)
				(justify left bottom)
				(hide yes)
			)
		)
		(property "Description" ""
			(at 133.985 177.8 0)
			(effects
				(font
					(size 1.27 1.27)
				)
			)
		)
		(property "Author" "Antmicro"
			(at 142.875 185.42 0)
			(effects
				(font
					(size 1.27 1.27)
					(thickness 0.15)
				)
				(justify left bottom)
				(hide yes)
			)
		)
		(property "License" "Apache-2.0"
			(at 142.875 187.96 0)
			(effects
				(font
					(size 1.27 1.27)
					(thickness 0.15)
				)
				(justify left bottom)
				(hide yes)
			)
		)
		(pin "1"
		)
		(instances
			(project "lpddr4-test-board"
				(path ""
					(reference "#PWR0191")
					(unit 1)
				)
			)
		)
	)
	(symbol
		(lib_id "antmicropower:GND")
		(at 92.075 120.65 0)
		(unit 1)
		(exclude_from_sim no)
		(in_bom yes)
		(on_board yes)
		(dnp no)
		(property "Reference" "#PWR0205"
			(at 100.965 123.19 0)
			(effects
				(font
					(size 1.27 1.27)
					(thickness 0.15)
				)
				(justify left bottom)
				(hide yes)
			)
		)
		(property "Value" "GND"
			(at 90.17 125.095 0)
			(effects
				(font
					(size 1.27 1.27)
					(thickness 0.15)
				)
				(justify left bottom)
			)
		)
		(property "Footprint" ""
			(at 100.965 128.27 0)
			(effects
				(font
					(size 1.27 1.27)
					(thickness 0.15)
				)
				(justify left bottom)
				(hide yes)
			)
		)
		(property "Datasheet" ""
			(at 100.965 133.35 0)
			(effects
				(font
					(size 1.27 1.27)
					(thickness 0.15)
				)
				(justify left bottom)
				(hide yes)
			)
		)
		(property "Description" ""
			(at 92.075 120.65 0)
			(effects
				(font
					(size 1.27 1.27)
				)
			)
		)
		(property "Author" "Antmicro"
			(at 100.965 128.27 0)
			(effects
				(font
					(size 1.27 1.27)
					(thickness 0.15)
				)
				(justify left bottom)
				(hide yes)
			)
		)
		(property "License" "Apache-2.0"
			(at 100.965 130.81 0)
			(effects
				(font
					(size 1.27 1.27)
					(thickness 0.15)
				)
				(justify left bottom)
				(hide yes)
			)
		)
		(pin "1"
		)
		(instances
			(project "lpddr4-test-board"
				(path ""
					(reference "#PWR0205")
					(unit 1)
				)
			)
		)
	)
	(symbol
		(lib_id "antmicropower:GND")
		(at 140.97 177.8 0)
		(unit 1)
		(exclude_from_sim no)
		(in_bom yes)
		(on_board yes)
		(dnp no)
		(property "Reference" "#PWR0193"
			(at 149.86 180.34 0)
			(effects
				(font
					(size 1.27 1.27)
					(thickness 0.15)
				)
				(justify left bottom)
				(hide yes)
			)
		)
		(property "Value" "GND"
			(at 139.065 182.245 0)
			(effects
				(font
					(size 1.27 1.27)
					(thickness 0.15)
				)
				(justify left bottom)
			)
		)
		(property "Footprint" ""
			(at 149.86 185.42 0)
			(effects
				(font
					(size 1.27 1.27)
					(thickness 0.15)
				)
				(justify left bottom)
				(hide yes)
			)
		)
		(property "Datasheet" ""
			(at 149.86 190.5 0)
			(effects
				(font
					(size 1.27 1.27)
					(thickness 0.15)
				)
				(justify left bottom)
				(hide yes)
			)
		)
		(property "Description" ""
			(at 140.97 177.8 0)
			(effects
				(font
					(size 1.27 1.27)
				)
			)
		)
		(property "Author" "Antmicro"
			(at 149.86 185.42 0)
			(effects
				(font
					(size 1.27 1.27)
					(thickness 0.15)
				)
				(justify left bottom)
				(hide yes)
			)
		)
		(property "License" "Apache-2.0"
			(at 149.86 187.96 0)
			(effects
				(font
					(size 1.27 1.27)
					(thickness 0.15)
				)
				(justify left bottom)
				(hide yes)
			)
		)
		(pin "1"
		)
		(instances
			(project "lpddr4-test-board"
				(path ""
					(reference "#PWR0193")
					(unit 1)
				)
			)
		)
	)
	(symbol
		(lib_id "antmicropower:GND")
		(at 92.075 177.8 0)
		(unit 1)
		(exclude_from_sim no)
		(in_bom yes)
		(on_board yes)
		(dnp no)
		(property "Reference" "#PWR0212"
			(at 100.965 180.34 0)
			(effects
				(font
					(size 1.27 1.27)
					(thickness 0.15)
				)
				(justify left bottom)
				(hide yes)
			)
		)
		(property "Value" "GND"
			(at 90.17 182.245 0)
			(effects
				(font
					(size 1.27 1.27)
					(thickness 0.15)
				)
				(justify left bottom)
			)
		)
		(property "Footprint" ""
			(at 100.965 185.42 0)
			(effects
				(font
					(size 1.27 1.27)
					(thickness 0.15)
				)
				(justify left bottom)
				(hide yes)
			)
		)
		(property "Datasheet" ""
			(at 100.965 190.5 0)
			(effects
				(font
					(size 1.27 1.27)
					(thickness 0.15)
				)
				(justify left bottom)
				(hide yes)
			)
		)
		(property "Description" ""
			(at 92.075 177.8 0)
			(effects
				(font
					(size 1.27 1.27)
				)
			)
		)
		(property "Author" "Antmicro"
			(at 100.965 185.42 0)
			(effects
				(font
					(size 1.27 1.27)
					(thickness 0.15)
				)
				(justify left bottom)
				(hide yes)
			)
		)
		(property "License" "Apache-2.0"
			(at 100.965 187.96 0)
			(effects
				(font
					(size 1.27 1.27)
					(thickness 0.15)
				)
				(justify left bottom)
				(hide yes)
			)
		)
		(pin "1"
		)
		(instances
			(project "lpddr4-test-board"
				(path ""
					(reference "#PWR0212")
					(unit 1)
				)
			)
		)
	)
	(symbol
		(lib_id "antmicropower:GND")
		(at 147.955 177.8 0)
		(unit 1)
		(exclude_from_sim no)
		(in_bom yes)
		(on_board yes)
		(dnp no)
		(property "Reference" "#PWR0192"
			(at 156.845 180.34 0)
			(effects
				(font
					(size 1.27 1.27)
					(thickness 0.15)
				)
				(justify left bottom)
				(hide yes)
			)
		)
		(property "Value" "GND"
			(at 146.05 182.245 0)
			(effects
				(font
					(size 1.27 1.27)
					(thickness 0.15)
				)
				(justify left bottom)
			)
		)
		(property "Footprint" ""
			(at 156.845 185.42 0)
			(effects
				(font
					(size 1.27 1.27)
					(thickness 0.15)
				)
				(justify left bottom)
				(hide yes)
			)
		)
		(property "Datasheet" ""
			(at 156.845 190.5 0)
			(effects
				(font
					(size 1.27 1.27)
					(thickness 0.15)
				)
				(justify left bottom)
				(hide yes)
			)
		)
		(property "Description" ""
			(at 147.955 177.8 0)
			(effects
				(font
					(size 1.27 1.27)
				)
			)
		)
		(property "Author" "Antmicro"
			(at 156.845 185.42 0)
			(effects
				(font
					(size 1.27 1.27)
					(thickness 0.15)
				)
				(justify left bottom)
				(hide yes)
			)
		)
		(property "License" "Apache-2.0"
			(at 156.845 187.96 0)
			(effects
				(font
					(size 1.27 1.27)
					(thickness 0.15)
				)
				(justify left bottom)
				(hide yes)
			)
		)
		(pin "1"
		)
		(instances
			(project "lpddr4-test-board"
				(path ""
					(reference "#PWR0192")
					(unit 1)
				)
			)
		)
	)
	(symbol
		(lib_id "antmicropower:GND")
		(at 175.895 234.95 0)
		(unit 1)
		(exclude_from_sim no)
		(in_bom yes)
		(on_board yes)
		(dnp no)
		(property "Reference" "#PWR0185"
			(at 184.785 237.49 0)
			(effects
				(font
					(size 1.27 1.27)
					(thickness 0.15)
				)
				(justify left bottom)
				(hide yes)
			)
		)
		(property "Value" "GND"
			(at 173.99 239.395 0)
			(effects
				(font
					(size 1.27 1.27)
					(thickness 0.15)
				)
				(justify left bottom)
			)
		)
		(property "Footprint" ""
			(at 184.785 242.57 0)
			(effects
				(font
					(size 1.27 1.27)
					(thickness 0.15)
				)
				(justify left bottom)
				(hide yes)
			)
		)
		(property "Datasheet" ""
			(at 184.785 247.65 0)
			(effects
				(font
					(size 1.27 1.27)
					(thickness 0.15)
				)
				(justify left bottom)
				(hide yes)
			)
		)
		(property "Description" ""
			(at 175.895 234.95 0)
			(effects
				(font
					(size 1.27 1.27)
				)
			)
		)
		(property "Author" "Antmicro"
			(at 184.785 242.57 0)
			(effects
				(font
					(size 1.27 1.27)
					(thickness 0.15)
				)
				(justify left bottom)
				(hide yes)
			)
		)
		(property "License" "Apache-2.0"
			(at 184.785 245.11 0)
			(effects
				(font
					(size 1.27 1.27)
					(thickness 0.15)
				)
				(justify left bottom)
				(hide yes)
			)
		)
		(pin "1"
		)
		(instances
			(project "lpddr4-test-board"
				(path ""
					(reference "#PWR0185")
					(unit 1)
				)
			)
		)
	)
	(symbol
		(lib_id "antmicropower:GND")
		(at 99.06 196.85 0)
		(unit 1)
		(exclude_from_sim no)
		(in_bom yes)
		(on_board yes)
		(dnp no)
		(property "Reference" "#PWR0210"
			(at 107.95 199.39 0)
			(effects
				(font
					(size 1.27 1.27)
					(thickness 0.15)
				)
				(justify left bottom)
				(hide yes)
			)
		)
		(property "Value" "GND"
			(at 97.155 201.295 0)
			(effects
				(font
					(size 1.27 1.27)
					(thickness 0.15)
				)
				(justify left bottom)
			)
		)
		(property "Footprint" ""
			(at 107.95 204.47 0)
			(effects
				(font
					(size 1.27 1.27)
					(thickness 0.15)
				)
				(justify left bottom)
				(hide yes)
			)
		)
		(property "Datasheet" ""
			(at 107.95 209.55 0)
			(effects
				(font
					(size 1.27 1.27)
					(thickness 0.15)
				)
				(justify left bottom)
				(hide yes)
			)
		)
		(property "Description" ""
			(at 99.06 196.85 0)
			(effects
				(font
					(size 1.27 1.27)
				)
			)
		)
		(property "Author" "Antmicro"
			(at 107.95 204.47 0)
			(effects
				(font
					(size 1.27 1.27)
					(thickness 0.15)
				)
				(justify left bottom)
				(hide yes)
			)
		)
		(property "License" "Apache-2.0"
			(at 107.95 207.01 0)
			(effects
				(font
					(size 1.27 1.27)
					(thickness 0.15)
				)
				(justify left bottom)
				(hide yes)
			)
		)
		(pin "1"
		)
		(instances
			(project "lpddr4-test-board"
				(path ""
					(reference "#PWR0210")
					(unit 1)
				)
			)
		)
	)
	(symbol
		(lib_id "antmicropower:GND")
		(at 92.075 139.7 0)
		(unit 1)
		(exclude_from_sim no)
		(in_bom yes)
		(on_board yes)
		(dnp no)
		(property "Reference" "#PWR0261"
			(at 100.965 142.24 0)
			(effects
				(font
					(size 1.27 1.27)
					(thickness 0.15)
				)
				(justify left bottom)
				(hide yes)
			)
		)
		(property "Value" "GND"
			(at 90.17 144.145 0)
			(effects
				(font
					(size 1.27 1.27)
					(thickness 0.15)
				)
				(justify left bottom)
			)
		)
		(property "Footprint" ""
			(at 100.965 147.32 0)
			(effects
				(font
					(size 1.27 1.27)
					(thickness 0.15)
				)
				(justify left bottom)
				(hide yes)
			)
		)
		(property "Datasheet" ""
			(at 100.965 152.4 0)
			(effects
				(font
					(size 1.27 1.27)
					(thickness 0.15)
				)
				(justify left bottom)
				(hide yes)
			)
		)
		(property "Description" ""
			(at 92.075 139.7 0)
			(effects
				(font
					(size 1.27 1.27)
				)
			)
		)
		(property "Author" "Antmicro"
			(at 100.965 147.32 0)
			(effects
				(font
					(size 1.27 1.27)
					(thickness 0.15)
				)
				(justify left bottom)
				(hide yes)
			)
		)
		(property "License" "Apache-2.0"
			(at 100.965 149.86 0)
			(effects
				(font
					(size 1.27 1.27)
					(thickness 0.15)
				)
				(justify left bottom)
				(hide yes)
			)
		)
		(pin "1"
		)
		(instances
			(project "lpddr4-test-board"
				(path ""
					(reference "#PWR0261")
					(unit 1)
				)
			)
		)
	)
	(symbol
		(lib_id "antmicroFPGAChips:XC7K70T-FBG484")
		(at 314.96 113.03 0)
		(unit 1)
		(exclude_from_sim no)
		(in_bom yes)
		(on_board yes)
		(dnp no)
		(property "Reference" "U3"
			(at 320.04 104.775 0)
			(effects
				(font
					(size 1.27 1.27)
					(thickness 0.15)
				)
				(justify left bottom)
			)
		)
		(property "Value" "XC7K70T-FBG484"
			(at 368.3 118.11 0)
			(effects
				(font
					(size 1.27 1.27)
					(thickness 0.15)
				)
				(justify left bottom)
				(hide yes)
			)
		)
		(property "Footprint" "antmicro-footprints:BGA-484_23x23mm_Layout22x22_P1mm_FBG484"
			(at 368.3 120.65 0)
			(effects
				(font
					(size 1.27 1.27)
					(thickness 0.15)
				)
				(justify left bottom)
				(hide yes)
			)
		)
		(property "Datasheet" "https://docs.xilinx.com/v/u/en-US/ds182_Kintex_7_Data_Sheet"
			(at 368.3 123.19 0)
			(effects
				(font
					(size 1.27 1.27)
					(thickness 0.15)
				)
				(justify left bottom)
				(hide yes)
			)
		)
		(property "Description" ""
			(at 314.96 113.03 0)
			(effects
				(font
					(size 1.27 1.27)
				)
			)
		)
		(property "Manufacturer" "AMD-Xilinx"
			(at 368.3 125.73 0)
			(effects
				(font
					(size 1.27 1.27)
					(thickness 0.15)
				)
				(justify left bottom)
				(hide yes)
			)
		)
		(property "MPN" "XC7K70T-1FBG484C"
			(at 320.04 106.68 0)
			(effects
				(font
					(size 1.27 1.27)
					(thickness 0.15)
				)
				(justify left bottom)
			)
		)
		(property "Author" "Antmicro"
			(at 368.3 128.27 0)
			(effects
				(font
					(size 1.27 1.27)
					(thickness 0.15)
				)
				(justify left bottom)
				(hide yes)
			)
		)
		(property "License" "Apache-2.0"
			(at 368.3 130.81 0)
			(effects
				(font
					(size 1.27 1.27)
					(thickness 0.15)
				)
				(justify left bottom)
				(hide yes)
			)
		)
		(pin "A1"
		)
		(pin "A12"
		)
		(pin "A17"
		)
		(pin "A2"
		)
		(pin "A22"
		)
		(pin "A5"
		)
		(pin "A6"
		)
		(pin "A7"
		)
		(pin "AA12"
		)
		(pin "AA17"
		)
		(pin "AA2"
		)
		(pin "AA22"
		)
		(pin "AA7"
		)
		(pin "AB14"
		)
		(pin "AB19"
		)
		(pin "AB4"
		)
		(pin "AB9"
		)
		(pin "B14"
		)
		(pin "B19"
		)
		(pin "B3"
		)
		(pin "B4"
		)
		(pin "B7"
		)
		(pin "B9"
		)
		(pin "C1"
		)
		(pin "C11"
		)
		(pin "C16"
		)
		(pin "C2"
		)
		(pin "C21"
		)
		(pin "C5"
		)
		(pin "C6"
		)
		(pin "C7"
		)
		(pin "D13"
		)
		(pin "D18"
		)
		(pin "D3"
		)
		(pin "D4"
		)
		(pin "D7"
		)
		(pin "D8"
		)
		(pin "E1"
		)
		(pin "E10"
		)
		(pin "E15"
		)
		(pin "E2"
		)
		(pin "E20"
		)
		(pin "E5"
		)
		(pin "E6"
		)
		(pin "E7"
		)
		(pin "F12"
		)
		(pin "F17"
		)
		(pin "F22"
		)
		(pin "F3"
		)
		(pin "F4"
		)
		(pin "F7"
		)
		(pin "G1"
		)
		(pin "G14"
		)
		(pin "G19"
		)
		(pin "G2"
		)
		(pin "G5"
		)
		(pin "G6"
		)
		(pin "G9"
		)
		(pin "H1"
		)
		(pin "H11"
		)
		(pin "H16"
		)
		(pin "H2"
		)
		(pin "H21"
		)
		(pin "H3"
		)
		(pin "H4"
		)
		(pin "H5"
		)
		(pin "J1"
		)
		(pin "J10"
		)
		(pin "J11"
		)
		(pin "J12"
		)
		(pin "J13"
		)
		(pin "J14"
		)
		(pin "J15"
		)
		(pin "J18"
		)
		(pin "J2"
		)
		(pin "J3"
		)
		(pin "J4"
		)
		(pin "J7"
		)
		(pin "J8"
		)
		(pin "J9"
		)
		(pin "K10"
		)
		(pin "K11"
		)
		(pin "K12"
		)
		(pin "K13"
		)
		(pin "K14"
		)
		(pin "K15"
		)
		(pin "K20"
		)
		(pin "K5"
		)
		(pin "K8"
		)
		(pin "K9"
		)
		(pin "L10"
		)
		(pin "L13"
		)
		(pin "L14"
		)
		(pin "L15"
		)
		(pin "L17"
		)
		(pin "L2"
		)
		(pin "L22"
		)
		(pin "L8"
		)
		(pin "L9"
		)
		(pin "M10"
		)
		(pin "M13"
		)
		(pin "M14"
		)
		(pin "M15"
		)
		(pin "M19"
		)
		(pin "M4"
		)
		(pin "M8"
		)
		(pin "M9"
		)
		(pin "N1"
		)
		(pin "N10"
		)
		(pin "N13"
		)
		(pin "N14"
		)
		(pin "N15"
		)
		(pin "N16"
		)
		(pin "N21"
		)
		(pin "N6"
		)
		(pin "N7"
		)
		(pin "N8"
		)
		(pin "N9"
		)
		(pin "P10"
		)
		(pin "P11"
		)
		(pin "P12"
		)
		(pin "P13"
		)
		(pin "P14"
		)
		(pin "P15"
		)
		(pin "P18"
		)
		(pin "P3"
		)
		(pin "P7"
		)
		(pin "P8"
		)
		(pin "P9"
		)
		(pin "R10"
		)
		(pin "R11"
		)
		(pin "R12"
		)
		(pin "R13"
		)
		(pin "R14"
		)
		(pin "R15"
		)
		(pin "R20"
		)
		(pin "R5"
		)
		(pin "R8"
		)
		(pin "R9"
		)
		(pin "T12"
		)
		(pin "T17"
		)
		(pin "T2"
		)
		(pin "T22"
		)
		(pin "T7"
		)
		(pin "U14"
		)
		(pin "U19"
		)
		(pin "U4"
		)
		(pin "U9"
		)
		(pin "V1"
		)
		(pin "V11"
		)
		(pin "V16"
		)
		(pin "V21"
		)
		(pin "V6"
		)
		(pin "W13"
		)
		(pin "W18"
		)
		(pin "W3"
		)
		(pin "W8"
		)
		(pin "Y10"
		)
		(pin "Y15"
		)
		(pin "Y20"
		)
		(pin "Y5"
		)
		(pin "AB11"
		)
		(pin "AB12"
		)
		(pin "AB13"
		)
		(pin "AB5"
		)
		(pin "AB6"
		)
		(pin "G7"
		)
		(pin "H6"
		)
		(pin "H7"
		)
		(pin "J5"
		)
		(pin "J6"
		)
		(pin "K6"
		)
		(pin "K7"
		)
		(pin "L11"
		)
		(pin "L12"
		)
		(pin "L6"
		)
		(pin "L7"
		)
		(pin "M11"
		)
		(pin "M12"
		)
		(pin "M6"
		)
		(pin "M7"
		)
		(pin "N11"
		)
		(pin "N12"
		)
		(pin "P6"
		)
		(pin "A3"
		)
		(pin "A4"
		)
		(pin "B1"
		)
		(pin "B2"
		)
		(pin "B5"
		)
		(pin "B6"
		)
		(pin "C3"
		)
		(pin "C4"
		)
		(pin "D1"
		)
		(pin "D2"
		)
		(pin "D5"
		)
		(pin "D6"
		)
		(pin "E3"
		)
		(pin "E4"
		)
		(pin "F1"
		)
		(pin "F2"
		)
		(pin "F5"
		)
		(pin "F6"
		)
		(pin "G3"
		)
		(pin "G4"
		)
		(pin "AA1"
		)
		(pin "AA3"
		)
		(pin "AA4"
		)
		(pin "AB1"
		)
		(pin "AB2"
		)
		(pin "AB3"
		)
		(pin "K1"
		)
		(pin "K2"
		)
		(pin "K3"
		)
		(pin "K4"
		)
		(pin "L1"
		)
		(pin "L3"
		)
		(pin "L4"
		)
		(pin "L5"
		)
		(pin "M1"
		)
		(pin "M2"
		)
		(pin "M3"
		)
		(pin "M5"
		)
		(pin "N2"
		)
		(pin "N3"
		)
		(pin "N4"
		)
		(pin "N5"
		)
		(pin "P1"
		)
		(pin "P2"
		)
		(pin "P4"
		)
		(pin "P5"
		)
		(pin "R1"
		)
		(pin "R2"
		)
		(pin "R3"
		)
		(pin "R4"
		)
		(pin "T1"
		)
		(pin "T3"
		)
		(pin "T4"
		)
		(pin "T5"
		)
		(pin "U1"
		)
		(pin "U2"
		)
		(pin "U3"
		)
		(pin "U5"
		)
		(pin "V2"
		)
		(pin "V3"
		)
		(pin "V4"
		)
		(pin "V5"
		)
		(pin "W1"
		)
		(pin "W2"
		)
		(pin "W4"
		)
		(pin "W5"
		)
		(pin "Y1"
		)
		(pin "Y2"
		)
		(pin "Y3"
		)
		(pin "Y4"
		)
		(pin "AA10"
		)
		(pin "AA11"
		)
		(pin "AA13"
		)
		(pin "AA5"
		)
		(pin "AA6"
		)
		(pin "AA8"
		)
		(pin "AA9"
		)
		(pin "AB10"
		)
		(pin "AB7"
		)
		(pin "AB8"
		)
		(pin "R6"
		)
		(pin "R7"
		)
		(pin "T10"
		)
		(pin "T11"
		)
		(pin "T13"
		)
		(pin "T14"
		)
		(pin "T6"
		)
		(pin "T8"
		)
		(pin "T9"
		)
		(pin "U10"
		)
		(pin "U11"
		)
		(pin "U12"
		)
		(pin "U13"
		)
		(pin "U6"
		)
		(pin "U7"
		)
		(pin "U8"
		)
		(pin "V10"
		)
		(pin "V12"
		)
		(pin "V13"
		)
		(pin "V7"
		)
		(pin "V8"
		)
		(pin "V9"
		)
		(pin "W10"
		)
		(pin "W11"
		)
		(pin "W12"
		)
		(pin "W6"
		)
		(pin "W7"
		)
		(pin "W9"
		)
		(pin "Y11"
		)
		(pin "Y12"
		)
		(pin "Y13"
		)
		(pin "Y6"
		)
		(pin "Y7"
		)
		(pin "Y8"
		)
		(pin "Y9"
		)
		(pin "A10"
		)
		(pin "A11"
		)
		(pin "A8"
		)
		(pin "A9"
		)
		(pin "B10"
		)
		(pin "B11"
		)
		(pin "B8"
		)
		(pin "C10"
		)
		(pin "C8"
		)
		(pin "C9"
		)
		(pin "D10"
		)
		(pin "D11"
		)
		(pin "D9"
		)
		(pin "E11"
		)
		(pin "E12"
		)
		(pin "E13"
		)
		(pin "E8"
		)
		(pin "E9"
		)
		(pin "F10"
		)
		(pin "F11"
		)
		(pin "F13"
		)
		(pin "F14"
		)
		(pin "F8"
		)
		(pin "F9"
		)
		(pin "G10"
		)
		(pin "G11"
		)
		(pin "G12"
		)
		(pin "G13"
		)
		(pin "G8"
		)
		(pin "H10"
		)
		(pin "H12"
		)
		(pin "H13"
		)
		(pin "H14"
		)
		(pin "H8"
		)
		(pin "H9"
		)
		(pin "A13"
		)
		(pin "A14"
		)
		(pin "A15"
		)
		(pin "A16"
		)
		(pin "A18"
		)
		(pin "A19"
		)
		(pin "A20"
		)
		(pin "A21"
		)
		(pin "B12"
		)
		(pin "B13"
		)
		(pin "B15"
		)
		(pin "B16"
		)
		(pin "B17"
		)
		(pin "B18"
		)
		(pin "B20"
		)
		(pin "B21"
		)
		(pin "B22"
		)
		(pin "C12"
		)
		(pin "C13"
		)
		(pin "C14"
		)
		(pin "C15"
		)
		(pin "C17"
		)
		(pin "C18"
		)
		(pin "C19"
		)
		(pin "C20"
		)
		(pin "C22"
		)
		(pin "D12"
		)
		(pin "D14"
		)
		(pin "D15"
		)
		(pin "D16"
		)
		(pin "D17"
		)
		(pin "D19"
		)
		(pin "D20"
		)
		(pin "D21"
		)
		(pin "D22"
		)
		(pin "E14"
		)
		(pin "E16"
		)
		(pin "E17"
		)
		(pin "E18"
		)
		(pin "E19"
		)
		(pin "F15"
		)
		(pin "F16"
		)
		(pin "F18"
		)
		(pin "G15"
		)
		(pin "G16"
		)
		(pin "G17"
		)
		(pin "H15"
		)
		(pin "H17"
		)
		(pin "J16"
		)
		(pin "J17"
		)
		(pin "E21"
		)
		(pin "E22"
		)
		(pin "F19"
		)
		(pin "F20"
		)
		(pin "F21"
		)
		(pin "G18"
		)
		(pin "G20"
		)
		(pin "G21"
		)
		(pin "G22"
		)
		(pin "H18"
		)
		(pin "H19"
		)
		(pin "H20"
		)
		(pin "H22"
		)
		(pin "J19"
		)
		(pin "J20"
		)
		(pin "J21"
		)
		(pin "J22"
		)
		(pin "K16"
		)
		(pin "K17"
		)
		(pin "K18"
		)
		(pin "K19"
		)
		(pin "K21"
		)
		(pin "K22"
		)
		(pin "L16"
		)
		(pin "L18"
		)
		(pin "L19"
		)
		(pin "L20"
		)
		(pin "L21"
		)
		(pin "M16"
		)
		(pin "M17"
		)
		(pin "M18"
		)
		(pin "M20"
		)
		(pin "M21"
		)
		(pin "M22"
		)
		(pin "N17"
		)
		(pin "N18"
		)
		(pin "N19"
		)
		(pin "N20"
		)
		(pin "N22"
		)
		(pin "P16"
		)
		(pin "P17"
		)
		(pin "P19"
		)
		(pin "P20"
		)
		(pin "P21"
		)
		(pin "P22"
		)
		(pin "R17"
		)
		(pin "R18"
		)
		(pin "R19"
		)
		(pin "R21"
		)
		(pin "R22"
		)
		(pin "AA14"
		)
		(pin "AA15"
		)
		(pin "AA16"
		)
		(pin "AA18"
		)
		(pin "AA19"
		)
		(pin "AA20"
		)
		(pin "AA21"
		)
		(pin "AB15"
		)
		(pin "AB16"
		)
		(pin "AB17"
		)
		(pin "AB18"
		)
		(pin "AB20"
		)
		(pin "AB21"
		)
		(pin "AB22"
		)
		(pin "R16"
		)
		(pin "T15"
		)
		(pin "T16"
		)
		(pin "T18"
		)
		(pin "T19"
		)
		(pin "T20"
		)
		(pin "T21"
		)
		(pin "U15"
		)
		(pin "U16"
		)
		(pin "U17"
		)
		(pin "U18"
		)
		(pin "U20"
		)
		(pin "U21"
		)
		(pin "U22"
		)
		(pin "V14"
		)
		(pin "V15"
		)
		(pin "V17"
		)
		(pin "V18"
		)
		(pin "V19"
		)
		(pin "V20"
		)
		(pin "V22"
		)
		(pin "W14"
		)
		(pin "W15"
		)
		(pin "W16"
		)
		(pin "W17"
		)
		(pin "W19"
		)
		(pin "W20"
		)
		(pin "W21"
		)
		(pin "W22"
		)
		(pin "Y14"
		)
		(pin "Y16"
		)
		(pin "Y17"
		)
		(pin "Y18"
		)
		(pin "Y19"
		)
		(pin "Y21"
		)
		(pin "Y22"
		)
		(instances
			(project "lpddr4-test-board"
				(path ""
					(reference "U3")
					(unit 1)
				)
			)
		)
	)
	(symbol
		(lib_id "antmicropower:GND")
		(at 92.075 234.95 0)
		(unit 1)
		(exclude_from_sim no)
		(in_bom yes)
		(on_board yes)
		(dnp no)
		(property "Reference" "#PWR0234"
			(at 100.965 237.49 0)
			(effects
				(font
					(size 1.27 1.27)
					(thickness 0.15)
				)
				(justify left bottom)
				(hide yes)
			)
		)
		(property "Value" "GND"
			(at 90.17 239.395 0)
			(effects
				(font
					(size 1.27 1.27)
					(thickness 0.15)
				)
				(justify left bottom)
			)
		)
		(property "Footprint" ""
			(at 100.965 242.57 0)
			(effects
				(font
					(size 1.27 1.27)
					(thickness 0.15)
				)
				(justify left bottom)
				(hide yes)
			)
		)
		(property "Datasheet" ""
			(at 100.965 247.65 0)
			(effects
				(font
					(size 1.27 1.27)
					(thickness 0.15)
				)
				(justify left bottom)
				(hide yes)
			)
		)
		(property "Description" ""
			(at 92.075 234.95 0)
			(effects
				(font
					(size 1.27 1.27)
				)
			)
		)
		(property "Author" "Antmicro"
			(at 100.965 242.57 0)
			(effects
				(font
					(size 1.27 1.27)
					(thickness 0.15)
				)
				(justify left bottom)
				(hide yes)
			)
		)
		(property "License" "Apache-2.0"
			(at 100.965 245.11 0)
			(effects
				(font
					(size 1.27 1.27)
					(thickness 0.15)
				)
				(justify left bottom)
				(hide yes)
			)
		)
		(pin "1"
		)
		(instances
			(project "lpddr4-test-board"
				(path ""
					(reference "#PWR0234")
					(unit 1)
				)
			)
		)
	)
	(symbol
		(lib_id "antmicropower:GND")
		(at 99.06 158.75 0)
		(unit 1)
		(exclude_from_sim no)
		(in_bom yes)
		(on_board yes)
		(dnp no)
		(property "Reference" "#PWR0263"
			(at 107.95 161.29 0)
			(effects
				(font
					(size 1.27 1.27)
					(thickness 0.15)
				)
				(justify left bottom)
				(hide yes)
			)
		)
		(property "Value" "GND"
			(at 97.155 163.195 0)
			(effects
				(font
					(size 1.27 1.27)
					(thickness 0.15)
				)
				(justify left bottom)
			)
		)
		(property "Footprint" ""
			(at 107.95 166.37 0)
			(effects
				(font
					(size 1.27 1.27)
					(thickness 0.15)
				)
				(justify left bottom)
				(hide yes)
			)
		)
		(property "Datasheet" ""
			(at 107.95 171.45 0)
			(effects
				(font
					(size 1.27 1.27)
					(thickness 0.15)
				)
				(justify left bottom)
				(hide yes)
			)
		)
		(property "Description" ""
			(at 99.06 158.75 0)
			(effects
				(font
					(size 1.27 1.27)
				)
			)
		)
		(property "Author" "Antmicro"
			(at 107.95 166.37 0)
			(effects
				(font
					(size 1.27 1.27)
					(thickness 0.15)
				)
				(justify left bottom)
				(hide yes)
			)
		)
		(property "License" "Apache-2.0"
			(at 107.95 168.91 0)
			(effects
				(font
					(size 1.27 1.27)
					(thickness 0.15)
				)
				(justify left bottom)
				(hide yes)
			)
		)
		(pin "1"
		)
		(instances
			(project "lpddr4-test-board"
				(path ""
					(reference "#PWR0263")
					(unit 1)
				)
			)
		)
	)
	(symbol
		(lib_id "antmicropower:GND")
		(at 99.06 234.95 0)
		(unit 1)
		(exclude_from_sim no)
		(in_bom yes)
		(on_board yes)
		(dnp no)
		(property "Reference" "#PWR0222"
			(at 107.95 237.49 0)
			(effects
				(font
					(size 1.27 1.27)
					(thickness 0.15)
				)
				(justify left bottom)
				(hide yes)
			)
		)
		(property "Value" "GND"
			(at 97.155 239.395 0)
			(effects
				(font
					(size 1.27 1.27)
					(thickness 0.15)
				)
				(justify left bottom)
			)
		)
		(property "Footprint" ""
			(at 107.95 242.57 0)
			(effects
				(font
					(size 1.27 1.27)
					(thickness 0.15)
				)
				(justify left bottom)
				(hide yes)
			)
		)
		(property "Datasheet" ""
			(at 107.95 247.65 0)
			(effects
				(font
					(size 1.27 1.27)
					(thickness 0.15)
				)
				(justify left bottom)
				(hide yes)
			)
		)
		(property "Description" ""
			(at 99.06 234.95 0)
			(effects
				(font
					(size 1.27 1.27)
				)
			)
		)
		(property "Author" "Antmicro"
			(at 107.95 242.57 0)
			(effects
				(font
					(size 1.27 1.27)
					(thickness 0.15)
				)
				(justify left bottom)
				(hide yes)
			)
		)
		(property "License" "Apache-2.0"
			(at 107.95 245.11 0)
			(effects
				(font
					(size 1.27 1.27)
					(thickness 0.15)
				)
				(justify left bottom)
				(hide yes)
			)
		)
		(pin "1"
		)
		(instances
			(project "lpddr4-test-board"
				(path ""
					(reference "#PWR0222")
					(unit 1)
				)
			)
		)
	)
	(symbol
		(lib_id "antmicropower:GND")
		(at 106.045 139.7 0)
		(unit 1)
		(exclude_from_sim no)
		(in_bom yes)
		(on_board yes)
		(dnp no)
		(property "Reference" "#PWR0260"
			(at 114.935 142.24 0)
			(effects
				(font
					(size 1.27 1.27)
					(thickness 0.15)
				)
				(justify left bottom)
				(hide yes)
			)
		)
		(property "Value" "GND"
			(at 104.14 144.145 0)
			(effects
				(font
					(size 1.27 1.27)
					(thickness 0.15)
				)
				(justify left bottom)
			)
		)
		(property "Footprint" ""
			(at 114.935 147.32 0)
			(effects
				(font
					(size 1.27 1.27)
					(thickness 0.15)
				)
				(justify left bottom)
				(hide yes)
			)
		)
		(property "Datasheet" ""
			(at 114.935 152.4 0)
			(effects
				(font
					(size 1.27 1.27)
					(thickness 0.15)
				)
				(justify left bottom)
				(hide yes)
			)
		)
		(property "Description" ""
			(at 106.045 139.7 0)
			(effects
				(font
					(size 1.27 1.27)
				)
			)
		)
		(property "Author" "Antmicro"
			(at 114.935 147.32 0)
			(effects
				(font
					(size 1.27 1.27)
					(thickness 0.15)
				)
				(justify left bottom)
				(hide yes)
			)
		)
		(property "License" "Apache-2.0"
			(at 114.935 149.86 0)
			(effects
				(font
					(size 1.27 1.27)
					(thickness 0.15)
				)
				(justify left bottom)
				(hide yes)
			)
		)
		(pin "1"
		)
		(instances
			(project "lpddr4-test-board"
				(path ""
					(reference "#PWR0260")
					(unit 1)
				)
			)
		)
	)
	(symbol
		(lib_id "antmicropower:GND")
		(at 127 177.8 0)
		(unit 1)
		(exclude_from_sim no)
		(in_bom yes)
		(on_board yes)
		(dnp no)
		(property "Reference" "#PWR0188"
			(at 135.89 180.34 0)
			(effects
				(font
					(size 1.27 1.27)
					(thickness 0.15)
				)
				(justify left bottom)
				(hide yes)
			)
		)
		(property "Value" "GND"
			(at 125.095 182.245 0)
			(effects
				(font
					(size 1.27 1.27)
					(thickness 0.15)
				)
				(justify left bottom)
			)
		)
		(property "Footprint" ""
			(at 135.89 185.42 0)
			(effects
				(font
					(size 1.27 1.27)
					(thickness 0.15)
				)
				(justify left bottom)
				(hide yes)
			)
		)
		(property "Datasheet" ""
			(at 135.89 190.5 0)
			(effects
				(font
					(size 1.27 1.27)
					(thickness 0.15)
				)
				(justify left bottom)
				(hide yes)
			)
		)
		(property "Description" ""
			(at 127 177.8 0)
			(effects
				(font
					(size 1.27 1.27)
				)
			)
		)
		(property "Author" "Antmicro"
			(at 135.89 185.42 0)
			(effects
				(font
					(size 1.27 1.27)
					(thickness 0.15)
				)
				(justify left bottom)
				(hide yes)
			)
		)
		(property "License" "Apache-2.0"
			(at 135.89 187.96 0)
			(effects
				(font
					(size 1.27 1.27)
					(thickness 0.15)
				)
				(justify left bottom)
				(hide yes)
			)
		)
		(pin "1"
		)
		(instances
			(project "lpddr4-test-board"
				(path ""
					(reference "#PWR0188")
					(unit 1)
				)
			)
		)
	)
	(symbol
		(lib_id "antmicropower:GND")
		(at 113.03 120.65 0)
		(unit 1)
		(exclude_from_sim no)
		(in_bom yes)
		(on_board yes)
		(dnp no)
		(property "Reference" "#PWR0206"
			(at 121.92 123.19 0)
			(effects
				(font
					(size 1.27 1.27)
					(thickness 0.15)
				)
				(justify left bottom)
				(hide yes)
			)
		)
		(property "Value" "GND"
			(at 111.125 125.095 0)
			(effects
				(font
					(size 1.27 1.27)
					(thickness 0.15)
				)
				(justify left bottom)
			)
		)
		(property "Footprint" ""
			(at 121.92 128.27 0)
			(effects
				(font
					(size 1.27 1.27)
					(thickness 0.15)
				)
				(justify left bottom)
				(hide yes)
			)
		)
		(property "Datasheet" ""
			(at 121.92 133.35 0)
			(effects
				(font
					(size 1.27 1.27)
					(thickness 0.15)
				)
				(justify left bottom)
				(hide yes)
			)
		)
		(property "Description" ""
			(at 113.03 120.65 0)
			(effects
				(font
					(size 1.27 1.27)
				)
			)
		)
		(property "Author" "Antmicro"
			(at 121.92 128.27 0)
			(effects
				(font
					(size 1.27 1.27)
					(thickness 0.15)
				)
				(justify left bottom)
				(hide yes)
			)
		)
		(property "License" "Apache-2.0"
			(at 121.92 130.81 0)
			(effects
				(font
					(size 1.27 1.27)
					(thickness 0.15)
				)
				(justify left bottom)
				(hide yes)
			)
		)
		(pin "1"
		)
		(instances
			(project "lpddr4-test-board"
				(path ""
					(reference "#PWR0206")
					(unit 1)
				)
			)
		)
	)
	(symbol
		(lib_id "antmicropower:GND")
		(at 203.835 234.95 0)
		(unit 1)
		(exclude_from_sim no)
		(in_bom yes)
		(on_board yes)
		(dnp no)
		(property "Reference" "#PWR0174"
			(at 212.725 237.49 0)
			(effects
				(font
					(size 1.27 1.27)
					(thickness 0.15)
				)
				(justify left bottom)
				(hide yes)
			)
		)
		(property "Value" "GND"
			(at 201.93 239.395 0)
			(effects
				(font
					(size 1.27 1.27)
					(thickness 0.15)
				)
				(justify left bottom)
			)
		)
		(property "Footprint" ""
			(at 212.725 242.57 0)
			(effects
				(font
					(size 1.27 1.27)
					(thickness 0.15)
				)
				(justify left bottom)
				(hide yes)
			)
		)
		(property "Datasheet" ""
			(at 212.725 247.65 0)
			(effects
				(font
					(size 1.27 1.27)
					(thickness 0.15)
				)
				(justify left bottom)
				(hide yes)
			)
		)
		(property "Description" ""
			(at 203.835 234.95 0)
			(effects
				(font
					(size 1.27 1.27)
				)
			)
		)
		(property "Author" "Antmicro"
			(at 212.725 242.57 0)
			(effects
				(font
					(size 1.27 1.27)
					(thickness 0.15)
				)
				(justify left bottom)
				(hide yes)
			)
		)
		(property "License" "Apache-2.0"
			(at 212.725 245.11 0)
			(effects
				(font
					(size 1.27 1.27)
					(thickness 0.15)
				)
				(justify left bottom)
				(hide yes)
			)
		)
		(pin "1"
		)
		(instances
			(project "lpddr4-test-board"
				(path ""
					(reference "#PWR0174")
					(unit 1)
				)
			)
		)
	)
	(symbol
		(lib_id "antmicropower:GND")
		(at 127 139.7 0)
		(unit 1)
		(exclude_from_sim no)
		(in_bom yes)
		(on_board yes)
		(dnp no)
		(property "Reference" "#PWR0198"
			(at 135.89 142.24 0)
			(effects
				(font
					(size 1.27 1.27)
					(thickness 0.15)
				)
				(justify left bottom)
				(hide yes)
			)
		)
		(property "Value" "GND"
			(at 125.095 144.145 0)
			(effects
				(font
					(size 1.27 1.27)
					(thickness 0.15)
				)
				(justify left bottom)
			)
		)
		(property "Footprint" ""
			(at 135.89 147.32 0)
			(effects
				(font
					(size 1.27 1.27)
					(thickness 0.15)
				)
				(justify left bottom)
				(hide yes)
			)
		)
		(property "Datasheet" ""
			(at 135.89 152.4 0)
			(effects
				(font
					(size 1.27 1.27)
					(thickness 0.15)
				)
				(justify left bottom)
				(hide yes)
			)
		)
		(property "Description" ""
			(at 127 139.7 0)
			(effects
				(font
					(size 1.27 1.27)
				)
			)
		)
		(property "Author" "Antmicro"
			(at 135.89 147.32 0)
			(effects
				(font
					(size 1.27 1.27)
					(thickness 0.15)
				)
				(justify left bottom)
				(hide yes)
			)
		)
		(property "License" "Apache-2.0"
			(at 135.89 149.86 0)
			(effects
				(font
					(size 1.27 1.27)
					(thickness 0.15)
				)
				(justify left bottom)
				(hide yes)
			)
		)
		(pin "1"
		)
		(instances
			(project "lpddr4-test-board"
				(path ""
					(reference "#PWR0198")
					(unit 1)
				)
			)
		)
	)
)
